G04*
G04 #@! TF.GenerationSoftware,Altium Limited,Altium Designer,22.4.2 (48)*
G04*
G04 Layer_Color=16711935*
%FSLAX25Y25*%
%MOIN*%
G70*
G04*
G04 #@! TF.SameCoordinates,446674BB-F454-490D-8607-5140536C8ADF*
G04*
G04*
G04 #@! TF.FilePolarity,Positive*
G04*
G01*
G75*
%ADD13C,0.00787*%
%ADD14C,0.00394*%
%ADD178C,0.00300*%
%ADD179C,0.00400*%
%ADD180R,0.00847X0.03150*%
G36*
X583655Y-174897D02*
X583314D01*
Y-172640D01*
X582053D01*
Y-172336D01*
X583655D01*
Y-174897D01*
D02*
G37*
G36*
X581823Y-172340D02*
Y-172355D01*
Y-172377D01*
X581819Y-172407D01*
X581816Y-172440D01*
X581808Y-172477D01*
X581801Y-172514D01*
X581786Y-172555D01*
Y-172558D01*
X581782Y-172562D01*
X581775Y-172584D01*
X581760Y-172617D01*
X581738Y-172662D01*
X581708Y-172714D01*
X581671Y-172773D01*
X581631Y-172832D01*
X581579Y-172895D01*
Y-172899D01*
X581572Y-172902D01*
X581553Y-172925D01*
X581520Y-172958D01*
X581472Y-173006D01*
X581416Y-173062D01*
X581346Y-173128D01*
X581261Y-173202D01*
X581168Y-173280D01*
X581165Y-173284D01*
X581150Y-173295D01*
X581128Y-173313D01*
X581102Y-173335D01*
X581068Y-173365D01*
X581028Y-173398D01*
X580987Y-173435D01*
X580939Y-173476D01*
X580846Y-173565D01*
X580754Y-173653D01*
X580710Y-173698D01*
X580669Y-173742D01*
X580632Y-173783D01*
X580602Y-173824D01*
Y-173827D01*
X580595Y-173831D01*
X580587Y-173842D01*
X580580Y-173857D01*
X580554Y-173898D01*
X580524Y-173946D01*
X580499Y-174005D01*
X580473Y-174068D01*
X580458Y-174138D01*
X580450Y-174205D01*
Y-174208D01*
Y-174212D01*
X580454Y-174234D01*
X580458Y-174271D01*
X580469Y-174312D01*
X580484Y-174364D01*
X580510Y-174416D01*
X580543Y-174468D01*
X580587Y-174519D01*
X580595Y-174527D01*
X580613Y-174541D01*
X580639Y-174560D01*
X580680Y-174586D01*
X580732Y-174608D01*
X580791Y-174630D01*
X580861Y-174645D01*
X580939Y-174649D01*
X580961D01*
X580976Y-174645D01*
X581020Y-174641D01*
X581072Y-174630D01*
X581128Y-174616D01*
X581190Y-174590D01*
X581250Y-174556D01*
X581305Y-174512D01*
X581313Y-174504D01*
X581327Y-174486D01*
X581350Y-174456D01*
X581372Y-174412D01*
X581398Y-174360D01*
X581420Y-174294D01*
X581435Y-174220D01*
X581442Y-174135D01*
X581764Y-174168D01*
Y-174171D01*
X581760Y-174183D01*
Y-174201D01*
X581756Y-174227D01*
X581749Y-174257D01*
X581742Y-174290D01*
X581731Y-174331D01*
X581719Y-174371D01*
X581690Y-174460D01*
X581646Y-174549D01*
X581620Y-174593D01*
X581586Y-174638D01*
X581553Y-174678D01*
X581516Y-174715D01*
X581512Y-174719D01*
X581505Y-174723D01*
X581494Y-174734D01*
X581475Y-174745D01*
X581453Y-174760D01*
X581427Y-174775D01*
X581398Y-174793D01*
X581361Y-174812D01*
X581320Y-174830D01*
X581276Y-174849D01*
X581227Y-174863D01*
X581176Y-174878D01*
X581120Y-174889D01*
X581061Y-174900D01*
X580998Y-174904D01*
X580932Y-174908D01*
X580894D01*
X580868Y-174904D01*
X580839Y-174900D01*
X580802Y-174897D01*
X580761Y-174889D01*
X580721Y-174882D01*
X580624Y-174856D01*
X580528Y-174819D01*
X580480Y-174797D01*
X580432Y-174771D01*
X580388Y-174738D01*
X580347Y-174701D01*
X580343Y-174697D01*
X580336Y-174693D01*
X580328Y-174678D01*
X580314Y-174664D01*
X580295Y-174645D01*
X580277Y-174619D01*
X580258Y-174593D01*
X580236Y-174560D01*
X580199Y-174490D01*
X580162Y-174401D01*
X580147Y-174356D01*
X580140Y-174305D01*
X580132Y-174253D01*
X580128Y-174197D01*
Y-174190D01*
Y-174171D01*
X580132Y-174142D01*
X580136Y-174101D01*
X580143Y-174057D01*
X580158Y-174005D01*
X580173Y-173950D01*
X580195Y-173894D01*
X580199Y-173887D01*
X580206Y-173868D01*
X580221Y-173838D01*
X580243Y-173798D01*
X580273Y-173753D01*
X580310Y-173698D01*
X580354Y-173642D01*
X580406Y-173580D01*
X580413Y-173572D01*
X580432Y-173550D01*
X580450Y-173531D01*
X580469Y-173513D01*
X580491Y-173491D01*
X580521Y-173461D01*
X580550Y-173432D01*
X580587Y-173398D01*
X580624Y-173361D01*
X580669Y-173320D01*
X580717Y-173280D01*
X580769Y-173232D01*
X580828Y-173184D01*
X580887Y-173132D01*
X580891Y-173128D01*
X580898Y-173121D01*
X580913Y-173110D01*
X580932Y-173095D01*
X580954Y-173073D01*
X580980Y-173050D01*
X581039Y-173002D01*
X581102Y-172947D01*
X581161Y-172891D01*
X581213Y-172843D01*
X581235Y-172825D01*
X581253Y-172806D01*
X581257Y-172802D01*
X581268Y-172791D01*
X581283Y-172777D01*
X581301Y-172754D01*
X581320Y-172729D01*
X581342Y-172703D01*
X581387Y-172640D01*
X580125D01*
Y-172336D01*
X581823D01*
Y-172340D01*
D02*
G37*
G36*
X569682Y-231903D02*
X567681D01*
X567685Y-231907D01*
X567699Y-231926D01*
X567722Y-231948D01*
X567747Y-231985D01*
X567781Y-232025D01*
X567818Y-232077D01*
X567858Y-232136D01*
X567899Y-232203D01*
Y-232207D01*
X567903Y-232210D01*
X567918Y-232233D01*
X567936Y-232270D01*
X567958Y-232314D01*
X567984Y-232366D01*
X568010Y-232421D01*
X568036Y-232477D01*
X568058Y-232532D01*
X567755D01*
Y-232529D01*
X567747Y-232521D01*
X567744Y-232506D01*
X567732Y-232488D01*
X567722Y-232466D01*
X567707Y-232440D01*
X567670Y-232377D01*
X567629Y-232303D01*
X567577Y-232229D01*
X567518Y-232151D01*
X567455Y-232073D01*
X567451Y-232070D01*
X567448Y-232066D01*
X567437Y-232055D01*
X567425Y-232040D01*
X567388Y-232007D01*
X567344Y-231962D01*
X567292Y-231918D01*
X567233Y-231870D01*
X567174Y-231829D01*
X567111Y-231792D01*
Y-231589D01*
X569682D01*
Y-231903D01*
D02*
G37*
G36*
X568698Y-233213D02*
X568735D01*
X568780Y-233217D01*
X568824Y-233221D01*
X568924Y-233232D01*
X569028Y-233246D01*
X569128Y-233269D01*
X569176Y-233283D01*
X569220Y-233298D01*
X569224D01*
X569231Y-233302D01*
X569242Y-233309D01*
X569257Y-233317D01*
X569298Y-233339D01*
X569349Y-233372D01*
X569409Y-233417D01*
X569468Y-233468D01*
X569531Y-233535D01*
X569586Y-233616D01*
Y-233620D01*
X569594Y-233628D01*
X569597Y-233639D01*
X569608Y-233657D01*
X569620Y-233679D01*
X569631Y-233709D01*
X569642Y-233738D01*
X569657Y-233775D01*
X569671Y-233816D01*
X569682Y-233861D01*
X569694Y-233909D01*
X569705Y-233964D01*
X569712Y-234020D01*
X569719Y-234079D01*
X569727Y-234212D01*
Y-234245D01*
X569723Y-234271D01*
Y-234301D01*
X569719Y-234338D01*
X569716Y-234379D01*
X569712Y-234419D01*
X569697Y-234512D01*
X569675Y-234612D01*
X569645Y-234708D01*
X569605Y-234800D01*
Y-234804D01*
X569597Y-234811D01*
X569590Y-234823D01*
X569583Y-234837D01*
X569553Y-234878D01*
X569512Y-234926D01*
X569460Y-234982D01*
X569401Y-235033D01*
X569327Y-235085D01*
X569246Y-235126D01*
X569242D01*
X569235Y-235130D01*
X569220Y-235133D01*
X569202Y-235141D01*
X569179Y-235148D01*
X569150Y-235156D01*
X569116Y-235167D01*
X569076Y-235174D01*
X569031Y-235181D01*
X568983Y-235193D01*
X568931Y-235200D01*
X568876Y-235207D01*
X568813Y-235215D01*
X568746Y-235219D01*
X568676Y-235222D01*
X568602D01*
X567122D01*
Y-234882D01*
X568602D01*
X568606D01*
X568617D01*
X568635D01*
X568657D01*
X568683Y-234878D01*
X568717D01*
X568787Y-234874D01*
X568868Y-234867D01*
X568950Y-234856D01*
X569028Y-234841D01*
X569061Y-234834D01*
X569094Y-234823D01*
X569102Y-234819D01*
X569120Y-234811D01*
X569146Y-234793D01*
X569183Y-234771D01*
X569220Y-234745D01*
X569261Y-234708D01*
X569301Y-234664D01*
X569335Y-234612D01*
X569338Y-234604D01*
X569349Y-234586D01*
X569360Y-234553D01*
X569375Y-234508D01*
X569394Y-234456D01*
X569405Y-234390D01*
X569416Y-234319D01*
X569420Y-234242D01*
Y-234205D01*
X569416Y-234183D01*
Y-234149D01*
X569412Y-234116D01*
X569397Y-234034D01*
X569379Y-233946D01*
X569349Y-233861D01*
X569309Y-233779D01*
X569283Y-233742D01*
X569253Y-233709D01*
X569249Y-233705D01*
X569246Y-233701D01*
X569235Y-233694D01*
X569220Y-233683D01*
X569198Y-233672D01*
X569176Y-233657D01*
X569142Y-233642D01*
X569109Y-233628D01*
X569068Y-233613D01*
X569020Y-233602D01*
X568965Y-233587D01*
X568905Y-233576D01*
X568839Y-233565D01*
X568769Y-233557D01*
X568687Y-233550D01*
X568602D01*
X567122D01*
Y-233209D01*
X568602D01*
X568606D01*
X568621D01*
X568639D01*
X568665D01*
X568698Y-233213D01*
D02*
G37*
G36*
X554471Y-233180D02*
X553283D01*
X553253Y-233176D01*
X553220D01*
X553142Y-233173D01*
X553061Y-233162D01*
X552972Y-233151D01*
X552891Y-233132D01*
X552850Y-233121D01*
X552817Y-233110D01*
X552813D01*
X552809Y-233106D01*
X552787Y-233095D01*
X552754Y-233080D01*
X552713Y-233054D01*
X552669Y-233021D01*
X552621Y-232977D01*
X552576Y-232925D01*
X552532Y-232866D01*
Y-232862D01*
X552528Y-232858D01*
X552513Y-232836D01*
X552498Y-232799D01*
X552476Y-232751D01*
X552458Y-232696D01*
X552439Y-232629D01*
X552428Y-232559D01*
X552424Y-232481D01*
Y-232477D01*
Y-232470D01*
Y-232455D01*
X552428Y-232436D01*
Y-232411D01*
X552432Y-232385D01*
X552447Y-232322D01*
X552469Y-232248D01*
X552498Y-232170D01*
X552543Y-232092D01*
X552572Y-232055D01*
X552602Y-232018D01*
X552606Y-232015D01*
X552609Y-232011D01*
X552621Y-232000D01*
X552635Y-231989D01*
X552654Y-231974D01*
X552676Y-231959D01*
X552706Y-231941D01*
X552735Y-231919D01*
X552772Y-231900D01*
X552813Y-231881D01*
X552857Y-231859D01*
X552906Y-231841D01*
X552961Y-231826D01*
X553016Y-231807D01*
X553079Y-231796D01*
X553146Y-231785D01*
X553139Y-231782D01*
X553124Y-231774D01*
X553102Y-231759D01*
X553072Y-231745D01*
X553005Y-231704D01*
X552972Y-231678D01*
X552943Y-231656D01*
X552935Y-231648D01*
X552917Y-231630D01*
X552887Y-231600D01*
X552850Y-231563D01*
X552809Y-231511D01*
X552761Y-231456D01*
X552713Y-231389D01*
X552661Y-231315D01*
X552221Y-230620D01*
X552643D01*
X552979Y-231153D01*
Y-231156D01*
X552987Y-231164D01*
X552994Y-231175D01*
X553005Y-231190D01*
X553031Y-231230D01*
X553064Y-231282D01*
X553105Y-231338D01*
X553146Y-231397D01*
X553187Y-231452D01*
X553224Y-231504D01*
X553227Y-231508D01*
X553238Y-231523D01*
X553257Y-231545D01*
X553283Y-231571D01*
X553338Y-231626D01*
X553368Y-231652D01*
X553398Y-231674D01*
X553401Y-231678D01*
X553409Y-231682D01*
X553423Y-231689D01*
X553446Y-231700D01*
X553468Y-231711D01*
X553494Y-231722D01*
X553553Y-231741D01*
X553557D01*
X553564Y-231745D01*
X553579D01*
X553597Y-231748D01*
X553623Y-231752D01*
X553653D01*
X553693Y-231756D01*
X554130D01*
Y-230620D01*
X554471D01*
Y-233180D01*
D02*
G37*
G36*
X552066Y-230624D02*
Y-230638D01*
Y-230661D01*
X552062Y-230690D01*
X552058Y-230723D01*
X552051Y-230760D01*
X552043Y-230797D01*
X552029Y-230838D01*
Y-230842D01*
X552025Y-230845D01*
X552017Y-230868D01*
X552003Y-230901D01*
X551980Y-230945D01*
X551951Y-230997D01*
X551914Y-231056D01*
X551873Y-231116D01*
X551821Y-231178D01*
Y-231182D01*
X551814Y-231186D01*
X551795Y-231208D01*
X551762Y-231241D01*
X551714Y-231290D01*
X551659Y-231345D01*
X551588Y-231412D01*
X551503Y-231486D01*
X551411Y-231563D01*
X551407Y-231567D01*
X551392Y-231578D01*
X551370Y-231597D01*
X551344Y-231619D01*
X551311Y-231648D01*
X551270Y-231682D01*
X551229Y-231719D01*
X551181Y-231759D01*
X551089Y-231848D01*
X550996Y-231937D01*
X550952Y-231981D01*
X550911Y-232026D01*
X550874Y-232066D01*
X550844Y-232107D01*
Y-232111D01*
X550837Y-232115D01*
X550830Y-232126D01*
X550822Y-232140D01*
X550797Y-232181D01*
X550767Y-232229D01*
X550741Y-232289D01*
X550715Y-232351D01*
X550700Y-232422D01*
X550693Y-232488D01*
Y-232492D01*
Y-232496D01*
X550697Y-232518D01*
X550700Y-232555D01*
X550711Y-232596D01*
X550726Y-232647D01*
X550752Y-232699D01*
X550785Y-232751D01*
X550830Y-232803D01*
X550837Y-232810D01*
X550856Y-232825D01*
X550881Y-232843D01*
X550922Y-232869D01*
X550974Y-232892D01*
X551033Y-232914D01*
X551103Y-232929D01*
X551181Y-232932D01*
X551203D01*
X551218Y-232929D01*
X551263Y-232925D01*
X551314Y-232914D01*
X551370Y-232899D01*
X551433Y-232873D01*
X551492Y-232840D01*
X551547Y-232795D01*
X551555Y-232788D01*
X551570Y-232769D01*
X551592Y-232740D01*
X551614Y-232696D01*
X551640Y-232644D01*
X551662Y-232577D01*
X551677Y-232503D01*
X551685Y-232418D01*
X552006Y-232451D01*
Y-232455D01*
X552003Y-232466D01*
Y-232485D01*
X551999Y-232510D01*
X551992Y-232540D01*
X551984Y-232573D01*
X551973Y-232614D01*
X551962Y-232655D01*
X551932Y-232744D01*
X551888Y-232832D01*
X551862Y-232877D01*
X551829Y-232921D01*
X551795Y-232962D01*
X551758Y-232999D01*
X551755Y-233003D01*
X551747Y-233006D01*
X551736Y-233017D01*
X551718Y-233029D01*
X551696Y-233043D01*
X551670Y-233058D01*
X551640Y-233077D01*
X551603Y-233095D01*
X551562Y-233114D01*
X551518Y-233132D01*
X551470Y-233147D01*
X551418Y-233162D01*
X551363Y-233173D01*
X551303Y-233184D01*
X551240Y-233188D01*
X551174Y-233191D01*
X551137D01*
X551111Y-233188D01*
X551081Y-233184D01*
X551044Y-233180D01*
X551004Y-233173D01*
X550963Y-233165D01*
X550867Y-233139D01*
X550771Y-233102D01*
X550723Y-233080D01*
X550674Y-233054D01*
X550630Y-233021D01*
X550589Y-232984D01*
X550586Y-232980D01*
X550578Y-232977D01*
X550571Y-232962D01*
X550556Y-232947D01*
X550537Y-232929D01*
X550519Y-232903D01*
X550500Y-232877D01*
X550478Y-232843D01*
X550441Y-232773D01*
X550404Y-232684D01*
X550389Y-232640D01*
X550382Y-232588D01*
X550375Y-232536D01*
X550371Y-232481D01*
Y-232473D01*
Y-232455D01*
X550375Y-232425D01*
X550378Y-232385D01*
X550386Y-232340D01*
X550401Y-232289D01*
X550415Y-232233D01*
X550438Y-232177D01*
X550441Y-232170D01*
X550449Y-232152D01*
X550463Y-232122D01*
X550486Y-232081D01*
X550515Y-232037D01*
X550552Y-231981D01*
X550597Y-231926D01*
X550648Y-231863D01*
X550656Y-231856D01*
X550674Y-231833D01*
X550693Y-231815D01*
X550711Y-231796D01*
X550734Y-231774D01*
X550763Y-231745D01*
X550793Y-231715D01*
X550830Y-231682D01*
X550867Y-231645D01*
X550911Y-231604D01*
X550959Y-231563D01*
X551011Y-231515D01*
X551070Y-231467D01*
X551129Y-231415D01*
X551133Y-231412D01*
X551140Y-231404D01*
X551155Y-231393D01*
X551174Y-231378D01*
X551196Y-231356D01*
X551222Y-231334D01*
X551281Y-231286D01*
X551344Y-231230D01*
X551403Y-231175D01*
X551455Y-231127D01*
X551477Y-231108D01*
X551496Y-231090D01*
X551499Y-231086D01*
X551510Y-231075D01*
X551525Y-231060D01*
X551544Y-231038D01*
X551562Y-231012D01*
X551585Y-230986D01*
X551629Y-230923D01*
X550367D01*
Y-230620D01*
X552066D01*
Y-230624D01*
D02*
G37*
G36*
X549646Y-239585D02*
X549676D01*
X549709Y-239588D01*
X549746Y-239596D01*
X549790Y-239607D01*
X549835Y-239618D01*
X549887Y-239633D01*
X549938Y-239651D01*
X549990Y-239673D01*
X550046Y-239703D01*
X550098Y-239736D01*
X550149Y-239773D01*
X550201Y-239818D01*
X550249Y-239869D01*
X550253Y-239873D01*
X550260Y-239884D01*
X550271Y-239899D01*
X550286Y-239925D01*
X550308Y-239958D01*
X550327Y-239995D01*
X550349Y-240043D01*
X550371Y-240095D01*
X550397Y-240158D01*
X550419Y-240228D01*
X550438Y-240306D01*
X550456Y-240391D01*
X550475Y-240487D01*
X550486Y-240591D01*
X550493Y-240702D01*
X550497Y-240820D01*
Y-240824D01*
Y-240828D01*
Y-240839D01*
Y-240854D01*
X550493Y-240891D01*
Y-240943D01*
X550490Y-241002D01*
X550482Y-241072D01*
X550475Y-241150D01*
X550464Y-241235D01*
X550449Y-241320D01*
X550430Y-241412D01*
X550408Y-241501D01*
X550382Y-241590D01*
X550349Y-241675D01*
X550312Y-241757D01*
X550271Y-241834D01*
X550223Y-241901D01*
X550220Y-241904D01*
X550212Y-241912D01*
X550197Y-241927D01*
X550179Y-241949D01*
X550157Y-241971D01*
X550127Y-241993D01*
X550090Y-242023D01*
X550053Y-242049D01*
X550009Y-242075D01*
X549961Y-242104D01*
X549905Y-242126D01*
X549850Y-242152D01*
X549787Y-242171D01*
X549720Y-242186D01*
X549650Y-242193D01*
X549576Y-242197D01*
X549546D01*
X549524Y-242193D01*
X549498D01*
X549469Y-242189D01*
X549398Y-242175D01*
X549321Y-242156D01*
X549239Y-242126D01*
X549158Y-242082D01*
X549117Y-242056D01*
X549080Y-242027D01*
X549076Y-242023D01*
X549073Y-242019D01*
X549061Y-242008D01*
X549050Y-241997D01*
X549032Y-241979D01*
X549017Y-241956D01*
X548976Y-241904D01*
X548936Y-241838D01*
X548899Y-241757D01*
X548865Y-241664D01*
X548843Y-241560D01*
X549158Y-241534D01*
Y-241538D01*
X549161Y-241542D01*
X549165Y-241564D01*
X549176Y-241597D01*
X549191Y-241638D01*
X549206Y-241683D01*
X549228Y-241727D01*
X549254Y-241768D01*
X549280Y-241801D01*
X549287Y-241808D01*
X549302Y-241823D01*
X549328Y-241845D01*
X549365Y-241871D01*
X549413Y-241893D01*
X549465Y-241916D01*
X549528Y-241930D01*
X549594Y-241938D01*
X549620D01*
X549650Y-241934D01*
X549683Y-241927D01*
X549727Y-241916D01*
X549772Y-241901D01*
X549816Y-241882D01*
X549861Y-241853D01*
X549868Y-241849D01*
X549887Y-241834D01*
X549913Y-241808D01*
X549946Y-241771D01*
X549983Y-241727D01*
X550024Y-241675D01*
X550061Y-241609D01*
X550098Y-241534D01*
Y-241531D01*
X550101Y-241523D01*
X550105Y-241512D01*
X550112Y-241497D01*
X550116Y-241475D01*
X550123Y-241449D01*
X550131Y-241420D01*
X550138Y-241383D01*
X550149Y-241342D01*
X550157Y-241298D01*
X550164Y-241250D01*
X550168Y-241198D01*
X550175Y-241139D01*
X550179Y-241079D01*
X550183Y-241013D01*
Y-240946D01*
X550179Y-240950D01*
X550164Y-240972D01*
X550138Y-241002D01*
X550105Y-241039D01*
X550068Y-241083D01*
X550020Y-241124D01*
X549968Y-241164D01*
X549909Y-241201D01*
X549905D01*
X549901Y-241205D01*
X549879Y-241216D01*
X549846Y-241227D01*
X549801Y-241246D01*
X549750Y-241261D01*
X549690Y-241272D01*
X549628Y-241283D01*
X549561Y-241287D01*
X549531D01*
X549509Y-241283D01*
X549480Y-241279D01*
X549450Y-241276D01*
X549413Y-241268D01*
X549376Y-241257D01*
X549291Y-241231D01*
X549247Y-241213D01*
X549202Y-241187D01*
X549158Y-241161D01*
X549110Y-241131D01*
X549065Y-241094D01*
X549024Y-241054D01*
X549021Y-241050D01*
X549013Y-241042D01*
X549002Y-241031D01*
X548991Y-241013D01*
X548973Y-240987D01*
X548954Y-240961D01*
X548936Y-240928D01*
X548913Y-240891D01*
X548891Y-240850D01*
X548873Y-240806D01*
X548854Y-240754D01*
X548836Y-240702D01*
X548825Y-240647D01*
X548814Y-240584D01*
X548806Y-240521D01*
X548803Y-240454D01*
Y-240450D01*
Y-240443D01*
Y-240432D01*
Y-240413D01*
X548806Y-240391D01*
Y-240369D01*
X548817Y-240310D01*
X548828Y-240240D01*
X548847Y-240165D01*
X548873Y-240084D01*
X548910Y-240006D01*
Y-240003D01*
X548913Y-239999D01*
X548921Y-239988D01*
X548928Y-239973D01*
X548950Y-239936D01*
X548984Y-239888D01*
X549024Y-239836D01*
X549073Y-239784D01*
X549132Y-239733D01*
X549195Y-239688D01*
X549198D01*
X549202Y-239685D01*
X549213Y-239677D01*
X549228Y-239673D01*
X549265Y-239655D01*
X549313Y-239636D01*
X549376Y-239614D01*
X549446Y-239599D01*
X549524Y-239585D01*
X549609Y-239581D01*
X549628D01*
X549646Y-239585D01*
D02*
G37*
G36*
X551903D02*
X551936D01*
X551977Y-239588D01*
X552022Y-239596D01*
X552073Y-239603D01*
X552181Y-239622D01*
X552292Y-239651D01*
X552403Y-239692D01*
X552454Y-239718D01*
X552506Y-239747D01*
X552510Y-239751D01*
X552517Y-239755D01*
X552532Y-239766D01*
X552547Y-239781D01*
X552569Y-239795D01*
X552595Y-239818D01*
X552625Y-239844D01*
X552654Y-239873D01*
X552684Y-239907D01*
X552717Y-239940D01*
X552784Y-240025D01*
X552847Y-240125D01*
X552902Y-240236D01*
Y-240240D01*
X552910Y-240251D01*
X552913Y-240269D01*
X552924Y-240291D01*
X552932Y-240321D01*
X552943Y-240358D01*
X552958Y-240399D01*
X552969Y-240443D01*
X552980Y-240491D01*
X552995Y-240547D01*
X553013Y-240661D01*
X553028Y-240791D01*
X553035Y-240924D01*
Y-240928D01*
Y-240943D01*
Y-240965D01*
X553032Y-240991D01*
Y-241028D01*
X553028Y-241065D01*
X553024Y-241113D01*
X553017Y-241161D01*
X552998Y-241268D01*
X552972Y-241387D01*
X552935Y-241505D01*
X552884Y-241620D01*
X552880Y-241623D01*
X552876Y-241634D01*
X552869Y-241649D01*
X552854Y-241668D01*
X552839Y-241694D01*
X552821Y-241723D01*
X552773Y-241790D01*
X552710Y-241864D01*
X552636Y-241938D01*
X552551Y-242012D01*
X552451Y-242075D01*
X552447Y-242078D01*
X552436Y-242082D01*
X552421Y-242090D01*
X552403Y-242101D01*
X552373Y-242112D01*
X552343Y-242123D01*
X552306Y-242138D01*
X552266Y-242152D01*
X552221Y-242167D01*
X552173Y-242182D01*
X552070Y-242204D01*
X551951Y-242223D01*
X551829Y-242230D01*
X551792D01*
X551766Y-242226D01*
X551733Y-242223D01*
X551692Y-242219D01*
X551651Y-242215D01*
X551603Y-242204D01*
X551504Y-242182D01*
X551393Y-242149D01*
X551337Y-242126D01*
X551285Y-242101D01*
X551233Y-242067D01*
X551182Y-242034D01*
X551178Y-242030D01*
X551170Y-242027D01*
X551156Y-242016D01*
X551137Y-241997D01*
X551119Y-241979D01*
X551093Y-241953D01*
X551067Y-241923D01*
X551037Y-241893D01*
X551008Y-241856D01*
X550978Y-241812D01*
X550945Y-241768D01*
X550915Y-241720D01*
X550889Y-241664D01*
X550860Y-241609D01*
X550838Y-241549D01*
X550815Y-241483D01*
X551148Y-241405D01*
Y-241409D01*
X551152Y-241416D01*
X551159Y-241431D01*
X551167Y-241449D01*
X551174Y-241472D01*
X551185Y-241501D01*
X551215Y-241560D01*
X551252Y-241627D01*
X551296Y-241694D01*
X551352Y-241757D01*
X551411Y-241812D01*
X551418Y-241819D01*
X551441Y-241834D01*
X551478Y-241853D01*
X551526Y-241879D01*
X551589Y-241901D01*
X551659Y-241923D01*
X551744Y-241938D01*
X551836Y-241941D01*
X551866D01*
X551885Y-241938D01*
X551910D01*
X551940Y-241934D01*
X552010Y-241923D01*
X552088Y-241908D01*
X552170Y-241882D01*
X552255Y-241845D01*
X552332Y-241797D01*
X552336D01*
X552340Y-241790D01*
X552366Y-241771D01*
X552399Y-241742D01*
X552440Y-241697D01*
X552488Y-241642D01*
X552532Y-241579D01*
X552573Y-241501D01*
X552610Y-241416D01*
Y-241412D01*
X552613Y-241405D01*
X552617Y-241394D01*
X552621Y-241375D01*
X552628Y-241353D01*
X552636Y-241327D01*
X552647Y-241264D01*
X552662Y-241190D01*
X552676Y-241109D01*
X552684Y-241020D01*
X552688Y-240924D01*
Y-240920D01*
Y-240909D01*
Y-240891D01*
Y-240868D01*
X552684Y-240843D01*
Y-240809D01*
X552680Y-240772D01*
X552676Y-240732D01*
X552665Y-240643D01*
X552647Y-240547D01*
X552625Y-240450D01*
X552595Y-240354D01*
Y-240351D01*
X552591Y-240343D01*
X552584Y-240332D01*
X552576Y-240314D01*
X552554Y-240269D01*
X552521Y-240217D01*
X552480Y-240158D01*
X552428Y-240095D01*
X552369Y-240040D01*
X552299Y-239988D01*
X552295D01*
X552288Y-239984D01*
X552277Y-239977D01*
X552262Y-239969D01*
X552244Y-239962D01*
X552221Y-239951D01*
X552170Y-239929D01*
X552103Y-239907D01*
X552029Y-239888D01*
X551947Y-239873D01*
X551862Y-239869D01*
X551836D01*
X551814Y-239873D01*
X551788D01*
X551762Y-239877D01*
X551696Y-239892D01*
X551618Y-239910D01*
X551541Y-239940D01*
X551459Y-239981D01*
X551418Y-240003D01*
X551381Y-240032D01*
X551378Y-240036D01*
X551374Y-240040D01*
X551363Y-240051D01*
X551348Y-240062D01*
X551333Y-240080D01*
X551315Y-240103D01*
X551293Y-240125D01*
X551274Y-240154D01*
X551252Y-240188D01*
X551226Y-240225D01*
X551204Y-240262D01*
X551182Y-240306D01*
X551163Y-240354D01*
X551145Y-240406D01*
X551126Y-240461D01*
X551111Y-240521D01*
X550771Y-240436D01*
Y-240432D01*
X550775Y-240417D01*
X550782Y-240395D01*
X550793Y-240365D01*
X550804Y-240332D01*
X550819Y-240291D01*
X550838Y-240247D01*
X550860Y-240199D01*
X550912Y-240095D01*
X550978Y-239992D01*
X551019Y-239940D01*
X551059Y-239888D01*
X551104Y-239844D01*
X551156Y-239799D01*
X551159Y-239795D01*
X551167Y-239788D01*
X551185Y-239781D01*
X551204Y-239766D01*
X551233Y-239747D01*
X551263Y-239729D01*
X551304Y-239710D01*
X551344Y-239692D01*
X551393Y-239670D01*
X551444Y-239651D01*
X551500Y-239633D01*
X551559Y-239614D01*
X551622Y-239599D01*
X551688Y-239592D01*
X551759Y-239585D01*
X551833Y-239581D01*
X551873D01*
X551903Y-239585D01*
D02*
G37*
G36*
X611004Y-237303D02*
X611041D01*
X611078Y-237307D01*
X611126Y-237311D01*
X611174Y-237318D01*
X611281Y-237336D01*
X611400Y-237362D01*
X611518Y-237399D01*
X611633Y-237451D01*
X611637Y-237455D01*
X611648Y-237458D01*
X611663Y-237466D01*
X611681Y-237481D01*
X611707Y-237495D01*
X611737Y-237514D01*
X611803Y-237562D01*
X611877Y-237625D01*
X611951Y-237699D01*
X612025Y-237784D01*
X612088Y-237884D01*
X612092Y-237888D01*
X612095Y-237899D01*
X612103Y-237914D01*
X612114Y-237932D01*
X612125Y-237962D01*
X612136Y-237991D01*
X612151Y-238028D01*
X612166Y-238069D01*
X612181Y-238113D01*
X612195Y-238161D01*
X612218Y-238265D01*
X612236Y-238384D01*
X612244Y-238506D01*
Y-238543D01*
X612240Y-238568D01*
X612236Y-238602D01*
X612232Y-238643D01*
X612229Y-238683D01*
X612218Y-238731D01*
X612195Y-238831D01*
X612162Y-238942D01*
X612140Y-238998D01*
X612114Y-239050D01*
X612081Y-239101D01*
X612047Y-239153D01*
X612044Y-239157D01*
X612040Y-239164D01*
X612029Y-239179D01*
X612010Y-239197D01*
X611992Y-239216D01*
X611966Y-239242D01*
X611936Y-239268D01*
X611907Y-239297D01*
X611870Y-239327D01*
X611825Y-239357D01*
X611781Y-239390D01*
X611733Y-239420D01*
X611677Y-239445D01*
X611622Y-239475D01*
X611563Y-239497D01*
X611496Y-239519D01*
X611418Y-239186D01*
X611422D01*
X611430Y-239183D01*
X611444Y-239175D01*
X611463Y-239168D01*
X611485Y-239160D01*
X611515Y-239149D01*
X611574Y-239120D01*
X611640Y-239083D01*
X611707Y-239038D01*
X611770Y-238983D01*
X611825Y-238924D01*
X611833Y-238916D01*
X611848Y-238894D01*
X611866Y-238857D01*
X611892Y-238809D01*
X611914Y-238746D01*
X611936Y-238676D01*
X611951Y-238591D01*
X611955Y-238498D01*
Y-238469D01*
X611951Y-238450D01*
Y-238424D01*
X611947Y-238395D01*
X611936Y-238324D01*
X611922Y-238247D01*
X611896Y-238165D01*
X611859Y-238080D01*
X611811Y-238002D01*
Y-237999D01*
X611803Y-237995D01*
X611785Y-237969D01*
X611755Y-237936D01*
X611711Y-237895D01*
X611655Y-237847D01*
X611592Y-237803D01*
X611515Y-237762D01*
X611430Y-237725D01*
X611426D01*
X611418Y-237721D01*
X611407Y-237718D01*
X611389Y-237714D01*
X611367Y-237706D01*
X611341Y-237699D01*
X611278Y-237688D01*
X611204Y-237673D01*
X611122Y-237658D01*
X611034Y-237651D01*
X610937Y-237647D01*
X610934D01*
X610923D01*
X610904D01*
X610882D01*
X610856Y-237651D01*
X610823D01*
X610786Y-237655D01*
X610745Y-237658D01*
X610656Y-237669D01*
X610560Y-237688D01*
X610464Y-237710D01*
X610368Y-237740D01*
X610364D01*
X610357Y-237743D01*
X610345Y-237751D01*
X610327Y-237758D01*
X610283Y-237780D01*
X610231Y-237814D01*
X610172Y-237854D01*
X610109Y-237906D01*
X610053Y-237965D01*
X610001Y-238036D01*
Y-238039D01*
X609998Y-238047D01*
X609990Y-238058D01*
X609983Y-238073D01*
X609975Y-238091D01*
X609964Y-238113D01*
X609942Y-238165D01*
X609920Y-238232D01*
X609901Y-238306D01*
X609887Y-238387D01*
X609883Y-238472D01*
Y-238498D01*
X609887Y-238520D01*
Y-238546D01*
X609890Y-238572D01*
X609905Y-238639D01*
X609924Y-238717D01*
X609953Y-238794D01*
X609994Y-238876D01*
X610016Y-238916D01*
X610046Y-238953D01*
X610049Y-238957D01*
X610053Y-238961D01*
X610064Y-238972D01*
X610075Y-238987D01*
X610094Y-239001D01*
X610116Y-239020D01*
X610138Y-239042D01*
X610168Y-239061D01*
X610201Y-239083D01*
X610238Y-239109D01*
X610275Y-239131D01*
X610320Y-239153D01*
X610368Y-239172D01*
X610419Y-239190D01*
X610475Y-239209D01*
X610534Y-239223D01*
X610449Y-239564D01*
X610445D01*
X610430Y-239560D01*
X610408Y-239553D01*
X610379Y-239542D01*
X610345Y-239530D01*
X610305Y-239516D01*
X610260Y-239497D01*
X610212Y-239475D01*
X610109Y-239423D01*
X610005Y-239357D01*
X609953Y-239316D01*
X609901Y-239275D01*
X609857Y-239231D01*
X609813Y-239179D01*
X609809Y-239175D01*
X609801Y-239168D01*
X609794Y-239149D01*
X609779Y-239131D01*
X609761Y-239101D01*
X609742Y-239072D01*
X609724Y-239031D01*
X609705Y-238990D01*
X609683Y-238942D01*
X609665Y-238890D01*
X609646Y-238835D01*
X609628Y-238776D01*
X609613Y-238713D01*
X609605Y-238646D01*
X609598Y-238576D01*
X609594Y-238502D01*
Y-238461D01*
X609598Y-238432D01*
Y-238398D01*
X609602Y-238358D01*
X609609Y-238313D01*
X609617Y-238261D01*
X609635Y-238154D01*
X609665Y-238043D01*
X609705Y-237932D01*
X609731Y-237880D01*
X609761Y-237828D01*
X609764Y-237825D01*
X609768Y-237817D01*
X609779Y-237803D01*
X609794Y-237788D01*
X609809Y-237766D01*
X609831Y-237740D01*
X609857Y-237710D01*
X609887Y-237681D01*
X609920Y-237651D01*
X609953Y-237618D01*
X610038Y-237551D01*
X610138Y-237488D01*
X610249Y-237433D01*
X610253D01*
X610264Y-237425D01*
X610283Y-237421D01*
X610305Y-237410D01*
X610334Y-237403D01*
X610371Y-237392D01*
X610412Y-237377D01*
X610456Y-237366D01*
X610504Y-237355D01*
X610560Y-237340D01*
X610675Y-237322D01*
X610804Y-237307D01*
X610937Y-237299D01*
X610941D01*
X610956D01*
X610978D01*
X611004Y-237303D01*
D02*
G37*
G36*
X611566Y-240097D02*
X611574Y-240104D01*
X611578Y-240119D01*
X611589Y-240137D01*
X611600Y-240160D01*
X611615Y-240185D01*
X611652Y-240248D01*
X611692Y-240322D01*
X611744Y-240396D01*
X611803Y-240474D01*
X611866Y-240552D01*
X611870Y-240555D01*
X611873Y-240559D01*
X611885Y-240570D01*
X611896Y-240585D01*
X611933Y-240618D01*
X611977Y-240663D01*
X612029Y-240707D01*
X612088Y-240755D01*
X612147Y-240796D01*
X612210Y-240833D01*
Y-241036D01*
X609639D01*
Y-240722D01*
X611640D01*
X611637Y-240718D01*
X611622Y-240700D01*
X611600Y-240677D01*
X611574Y-240640D01*
X611541Y-240600D01*
X611504Y-240548D01*
X611463Y-240489D01*
X611422Y-240422D01*
Y-240419D01*
X611418Y-240415D01*
X611404Y-240393D01*
X611385Y-240356D01*
X611363Y-240311D01*
X611337Y-240259D01*
X611311Y-240204D01*
X611285Y-240148D01*
X611263Y-240093D01*
X611566D01*
Y-240097D01*
D02*
G37*
G36*
X612199Y-242909D02*
Y-243164D01*
X610541D01*
Y-243512D01*
X610253D01*
Y-243164D01*
X609639D01*
Y-242849D01*
X610253D01*
Y-241736D01*
X610541D01*
X612199Y-242909D01*
D02*
G37*
G36*
X622004Y-237298D02*
X622041D01*
X622078Y-237301D01*
X622126Y-237305D01*
X622174Y-237312D01*
X622282Y-237331D01*
X622400Y-237357D01*
X622518Y-237394D01*
X622633Y-237445D01*
X622637Y-237449D01*
X622648Y-237453D01*
X622663Y-237460D01*
X622681Y-237475D01*
X622707Y-237490D01*
X622737Y-237508D01*
X622803Y-237557D01*
X622877Y-237619D01*
X622951Y-237693D01*
X623025Y-237778D01*
X623088Y-237878D01*
X623092Y-237882D01*
X623096Y-237893D01*
X623103Y-237908D01*
X623114Y-237927D01*
X623125Y-237956D01*
X623136Y-237986D01*
X623151Y-238023D01*
X623166Y-238063D01*
X623181Y-238108D01*
X623195Y-238156D01*
X623218Y-238260D01*
X623236Y-238378D01*
X623244Y-238500D01*
Y-238537D01*
X623240Y-238563D01*
X623236Y-238596D01*
X623232Y-238637D01*
X623229Y-238678D01*
X623218Y-238726D01*
X623195Y-238826D01*
X623162Y-238937D01*
X623140Y-238992D01*
X623114Y-239044D01*
X623081Y-239096D01*
X623047Y-239147D01*
X623044Y-239151D01*
X623040Y-239159D01*
X623029Y-239173D01*
X623010Y-239192D01*
X622992Y-239210D01*
X622966Y-239236D01*
X622936Y-239262D01*
X622907Y-239292D01*
X622870Y-239321D01*
X622825Y-239351D01*
X622781Y-239384D01*
X622733Y-239414D01*
X622677Y-239440D01*
X622622Y-239469D01*
X622563Y-239492D01*
X622496Y-239514D01*
X622418Y-239181D01*
X622422D01*
X622430Y-239177D01*
X622444Y-239170D01*
X622463Y-239162D01*
X622485Y-239155D01*
X622515Y-239144D01*
X622574Y-239114D01*
X622640Y-239077D01*
X622707Y-239033D01*
X622770Y-238977D01*
X622825Y-238918D01*
X622833Y-238911D01*
X622848Y-238889D01*
X622866Y-238851D01*
X622892Y-238803D01*
X622914Y-238740D01*
X622936Y-238670D01*
X622951Y-238585D01*
X622955Y-238493D01*
Y-238463D01*
X622951Y-238444D01*
Y-238419D01*
X622948Y-238389D01*
X622936Y-238319D01*
X622922Y-238241D01*
X622896Y-238160D01*
X622859Y-238074D01*
X622811Y-237997D01*
Y-237993D01*
X622803Y-237989D01*
X622785Y-237964D01*
X622755Y-237930D01*
X622711Y-237890D01*
X622655Y-237841D01*
X622592Y-237797D01*
X622515Y-237756D01*
X622430Y-237719D01*
X622426D01*
X622418Y-237716D01*
X622407Y-237712D01*
X622389Y-237708D01*
X622367Y-237701D01*
X622341Y-237693D01*
X622278Y-237682D01*
X622204Y-237667D01*
X622122Y-237653D01*
X622034Y-237645D01*
X621937Y-237642D01*
X621934D01*
X621923D01*
X621904D01*
X621882D01*
X621856Y-237645D01*
X621823D01*
X621786Y-237649D01*
X621745Y-237653D01*
X621656Y-237664D01*
X621560Y-237682D01*
X621464Y-237704D01*
X621368Y-237734D01*
X621364D01*
X621356Y-237738D01*
X621345Y-237745D01*
X621327Y-237753D01*
X621282Y-237775D01*
X621231Y-237808D01*
X621172Y-237849D01*
X621109Y-237901D01*
X621053Y-237960D01*
X621001Y-238030D01*
Y-238034D01*
X620998Y-238041D01*
X620990Y-238052D01*
X620983Y-238067D01*
X620975Y-238086D01*
X620964Y-238108D01*
X620942Y-238160D01*
X620920Y-238226D01*
X620901Y-238300D01*
X620887Y-238382D01*
X620883Y-238467D01*
Y-238493D01*
X620887Y-238515D01*
Y-238541D01*
X620890Y-238567D01*
X620905Y-238633D01*
X620924Y-238711D01*
X620953Y-238789D01*
X620994Y-238870D01*
X621016Y-238911D01*
X621046Y-238948D01*
X621049Y-238951D01*
X621053Y-238955D01*
X621064Y-238966D01*
X621075Y-238981D01*
X621094Y-238996D01*
X621116Y-239014D01*
X621138Y-239036D01*
X621168Y-239055D01*
X621201Y-239077D01*
X621238Y-239103D01*
X621275Y-239125D01*
X621319Y-239147D01*
X621368Y-239166D01*
X621419Y-239184D01*
X621475Y-239203D01*
X621534Y-239218D01*
X621449Y-239558D01*
X621445D01*
X621430Y-239555D01*
X621408Y-239547D01*
X621379Y-239536D01*
X621345Y-239525D01*
X621305Y-239510D01*
X621260Y-239492D01*
X621212Y-239469D01*
X621109Y-239418D01*
X621005Y-239351D01*
X620953Y-239310D01*
X620901Y-239270D01*
X620857Y-239225D01*
X620813Y-239173D01*
X620809Y-239170D01*
X620801Y-239162D01*
X620794Y-239144D01*
X620779Y-239125D01*
X620761Y-239096D01*
X620742Y-239066D01*
X620724Y-239025D01*
X620705Y-238985D01*
X620683Y-238937D01*
X620665Y-238885D01*
X620646Y-238829D01*
X620628Y-238770D01*
X620613Y-238707D01*
X620605Y-238641D01*
X620598Y-238570D01*
X620594Y-238496D01*
Y-238456D01*
X620598Y-238426D01*
Y-238393D01*
X620602Y-238352D01*
X620609Y-238308D01*
X620616Y-238256D01*
X620635Y-238148D01*
X620665Y-238037D01*
X620705Y-237927D01*
X620731Y-237875D01*
X620761Y-237823D01*
X620764Y-237819D01*
X620768Y-237812D01*
X620779Y-237797D01*
X620794Y-237782D01*
X620809Y-237760D01*
X620831Y-237734D01*
X620857Y-237704D01*
X620887Y-237675D01*
X620920Y-237645D01*
X620953Y-237612D01*
X621038Y-237545D01*
X621138Y-237483D01*
X621249Y-237427D01*
X621253D01*
X621264Y-237420D01*
X621282Y-237416D01*
X621305Y-237405D01*
X621334Y-237397D01*
X621371Y-237386D01*
X621412Y-237371D01*
X621456Y-237360D01*
X621504Y-237349D01*
X621560Y-237334D01*
X621675Y-237316D01*
X621804Y-237301D01*
X621937Y-237294D01*
X621941D01*
X621956D01*
X621978D01*
X622004Y-237298D01*
D02*
G37*
G36*
X622566Y-240091D02*
X622574Y-240098D01*
X622577Y-240113D01*
X622589Y-240132D01*
X622600Y-240154D01*
X622614Y-240180D01*
X622651Y-240243D01*
X622692Y-240317D01*
X622744Y-240391D01*
X622803Y-240468D01*
X622866Y-240546D01*
X622870Y-240550D01*
X622873Y-240553D01*
X622885Y-240565D01*
X622896Y-240579D01*
X622933Y-240613D01*
X622977Y-240657D01*
X623029Y-240702D01*
X623088Y-240750D01*
X623147Y-240790D01*
X623210Y-240827D01*
Y-241031D01*
X620639D01*
Y-240716D01*
X622640D01*
X622637Y-240713D01*
X622622Y-240694D01*
X622600Y-240672D01*
X622574Y-240635D01*
X622541Y-240594D01*
X622504Y-240542D01*
X622463Y-240483D01*
X622422Y-240417D01*
Y-240413D01*
X622418Y-240409D01*
X622404Y-240387D01*
X622385Y-240350D01*
X622363Y-240306D01*
X622337Y-240254D01*
X622311Y-240198D01*
X622285Y-240143D01*
X622263Y-240087D01*
X622566D01*
Y-240091D01*
D02*
G37*
G36*
X621356Y-242156D02*
X621353D01*
X621345Y-242159D01*
X621331Y-242163D01*
X621312Y-242167D01*
X621290Y-242170D01*
X621264Y-242178D01*
X621208Y-242196D01*
X621142Y-242222D01*
X621079Y-242255D01*
X621020Y-242292D01*
X620968Y-242337D01*
X620964Y-242344D01*
X620950Y-242359D01*
X620931Y-242389D01*
X620913Y-242426D01*
X620890Y-242470D01*
X620872Y-242526D01*
X620857Y-242588D01*
X620853Y-242655D01*
Y-242677D01*
X620857Y-242692D01*
X620861Y-242733D01*
X620872Y-242785D01*
X620890Y-242844D01*
X620916Y-242907D01*
X620953Y-242970D01*
X621005Y-243029D01*
X621012Y-243036D01*
X621035Y-243055D01*
X621068Y-243077D01*
X621112Y-243107D01*
X621168Y-243136D01*
X621231Y-243158D01*
X621305Y-243177D01*
X621386Y-243184D01*
X621390D01*
X621397D01*
X621408D01*
X621423Y-243180D01*
X621464Y-243177D01*
X621512Y-243166D01*
X621571Y-243151D01*
X621630Y-243125D01*
X621690Y-243088D01*
X621745Y-243040D01*
X621752Y-243033D01*
X621767Y-243014D01*
X621789Y-242984D01*
X621815Y-242944D01*
X621841Y-242892D01*
X621863Y-242829D01*
X621878Y-242759D01*
X621886Y-242681D01*
Y-242648D01*
X621882Y-242622D01*
X621878Y-242588D01*
X621871Y-242551D01*
X621863Y-242507D01*
X621852Y-242459D01*
X622130Y-242496D01*
Y-242514D01*
X622126Y-242529D01*
Y-242577D01*
X622133Y-242618D01*
X622141Y-242666D01*
X622152Y-242722D01*
X622170Y-242785D01*
X622196Y-242844D01*
X622230Y-242907D01*
Y-242910D01*
X622233Y-242914D01*
X622248Y-242933D01*
X622274Y-242958D01*
X622307Y-242988D01*
X622356Y-243018D01*
X622411Y-243044D01*
X622474Y-243062D01*
X622511Y-243070D01*
X622552D01*
X622555D01*
X622559D01*
X622581D01*
X622611Y-243062D01*
X622651Y-243055D01*
X622696Y-243040D01*
X622744Y-243021D01*
X622792Y-242992D01*
X622836Y-242951D01*
X622840Y-242947D01*
X622855Y-242929D01*
X622873Y-242903D01*
X622896Y-242870D01*
X622914Y-242825D01*
X622933Y-242774D01*
X622948Y-242714D01*
X622951Y-242648D01*
Y-242618D01*
X622944Y-242585D01*
X622936Y-242540D01*
X622922Y-242492D01*
X622903Y-242444D01*
X622873Y-242392D01*
X622836Y-242344D01*
X622833Y-242341D01*
X622814Y-242326D01*
X622788Y-242304D01*
X622751Y-242278D01*
X622703Y-242252D01*
X622644Y-242226D01*
X622574Y-242204D01*
X622492Y-242189D01*
X622548Y-241874D01*
X622552D01*
X622563Y-241878D01*
X622577Y-241882D01*
X622600Y-241885D01*
X622626Y-241893D01*
X622655Y-241904D01*
X622725Y-241926D01*
X622807Y-241963D01*
X622888Y-242008D01*
X622966Y-242063D01*
X623036Y-242133D01*
X623040Y-242137D01*
X623044Y-242144D01*
X623051Y-242156D01*
X623062Y-242170D01*
X623077Y-242189D01*
X623092Y-242215D01*
X623107Y-242241D01*
X623125Y-242274D01*
X623155Y-242348D01*
X623184Y-242433D01*
X623203Y-242533D01*
X623210Y-242585D01*
Y-242677D01*
X623207Y-242718D01*
X623199Y-242766D01*
X623188Y-242825D01*
X623170Y-242892D01*
X623147Y-242958D01*
X623118Y-243025D01*
Y-243029D01*
X623114Y-243033D01*
X623103Y-243055D01*
X623081Y-243088D01*
X623055Y-243125D01*
X623018Y-243169D01*
X622977Y-243214D01*
X622929Y-243258D01*
X622873Y-243295D01*
X622866Y-243299D01*
X622848Y-243310D01*
X622814Y-243325D01*
X622774Y-243343D01*
X622725Y-243362D01*
X622670Y-243377D01*
X622607Y-243388D01*
X622544Y-243391D01*
X622537D01*
X622515D01*
X622485Y-243388D01*
X622444Y-243380D01*
X622396Y-243369D01*
X622344Y-243351D01*
X622293Y-243328D01*
X622241Y-243299D01*
X622233Y-243295D01*
X622219Y-243284D01*
X622193Y-243262D01*
X622163Y-243232D01*
X622130Y-243195D01*
X622093Y-243151D01*
X622059Y-243099D01*
X622026Y-243036D01*
Y-243040D01*
X622022Y-243047D01*
X622019Y-243058D01*
X622015Y-243073D01*
X622000Y-243114D01*
X621978Y-243166D01*
X621948Y-243225D01*
X621911Y-243284D01*
X621863Y-243340D01*
X621808Y-243391D01*
X621801Y-243395D01*
X621778Y-243410D01*
X621741Y-243432D01*
X621693Y-243454D01*
X621634Y-243477D01*
X621564Y-243499D01*
X621482Y-243513D01*
X621393Y-243517D01*
X621390D01*
X621379D01*
X621360D01*
X621338Y-243513D01*
X621308Y-243510D01*
X621275Y-243502D01*
X621238Y-243495D01*
X621197Y-243488D01*
X621109Y-243458D01*
X621061Y-243436D01*
X621016Y-243414D01*
X620968Y-243384D01*
X620920Y-243351D01*
X620872Y-243314D01*
X620827Y-243269D01*
X620824Y-243266D01*
X620816Y-243258D01*
X620805Y-243243D01*
X620790Y-243225D01*
X620772Y-243203D01*
X620753Y-243173D01*
X620731Y-243140D01*
X620713Y-243099D01*
X620690Y-243058D01*
X620668Y-243010D01*
X620650Y-242962D01*
X620631Y-242907D01*
X620616Y-242847D01*
X620605Y-242785D01*
X620598Y-242722D01*
X620594Y-242651D01*
Y-242618D01*
X620598Y-242596D01*
X620602Y-242566D01*
X620605Y-242533D01*
X620613Y-242496D01*
X620620Y-242455D01*
X620642Y-242367D01*
X620679Y-242274D01*
X620702Y-242226D01*
X620727Y-242181D01*
X620761Y-242137D01*
X620794Y-242093D01*
X620798Y-242089D01*
X620805Y-242082D01*
X620816Y-242071D01*
X620831Y-242059D01*
X620850Y-242041D01*
X620876Y-242022D01*
X620901Y-242000D01*
X620935Y-241978D01*
X620972Y-241956D01*
X621009Y-241934D01*
X621098Y-241893D01*
X621201Y-241860D01*
X621257Y-241848D01*
X621316Y-241841D01*
X621356Y-242156D01*
D02*
G37*
G36*
X582633Y-228451D02*
X582655D01*
X582715Y-228462D01*
X582785Y-228473D01*
X582859Y-228492D01*
X582940Y-228518D01*
X583018Y-228555D01*
X583022D01*
X583025Y-228558D01*
X583036Y-228566D01*
X583051Y-228573D01*
X583088Y-228595D01*
X583136Y-228628D01*
X583188Y-228669D01*
X583240Y-228717D01*
X583292Y-228777D01*
X583336Y-228839D01*
Y-228843D01*
X583340Y-228847D01*
X583347Y-228858D01*
X583351Y-228873D01*
X583369Y-228910D01*
X583388Y-228958D01*
X583410Y-229021D01*
X583425Y-229091D01*
X583440Y-229169D01*
X583443Y-229254D01*
Y-229272D01*
X583440Y-229291D01*
Y-229320D01*
X583436Y-229354D01*
X583429Y-229391D01*
X583418Y-229435D01*
X583406Y-229480D01*
X583392Y-229531D01*
X583373Y-229583D01*
X583351Y-229635D01*
X583321Y-229690D01*
X583288Y-229742D01*
X583251Y-229794D01*
X583207Y-229846D01*
X583155Y-229894D01*
X583151Y-229898D01*
X583140Y-229905D01*
X583125Y-229916D01*
X583099Y-229931D01*
X583066Y-229953D01*
X583029Y-229972D01*
X582981Y-229994D01*
X582929Y-230016D01*
X582866Y-230042D01*
X582796Y-230064D01*
X582718Y-230083D01*
X582633Y-230101D01*
X582537Y-230120D01*
X582433Y-230131D01*
X582322Y-230138D01*
X582204Y-230142D01*
X582200D01*
X582197D01*
X582185D01*
X582171D01*
X582134Y-230138D01*
X582082D01*
X582023Y-230134D01*
X581952Y-230127D01*
X581875Y-230120D01*
X581789Y-230108D01*
X581704Y-230094D01*
X581612Y-230075D01*
X581523Y-230053D01*
X581434Y-230027D01*
X581349Y-229994D01*
X581268Y-229957D01*
X581190Y-229916D01*
X581123Y-229868D01*
X581120Y-229864D01*
X581112Y-229857D01*
X581098Y-229842D01*
X581075Y-229824D01*
X581053Y-229801D01*
X581031Y-229772D01*
X581001Y-229735D01*
X580975Y-229698D01*
X580950Y-229653D01*
X580920Y-229605D01*
X580898Y-229550D01*
X580872Y-229494D01*
X580853Y-229431D01*
X580839Y-229365D01*
X580831Y-229294D01*
X580828Y-229221D01*
Y-229191D01*
X580831Y-229169D01*
Y-229143D01*
X580835Y-229113D01*
X580850Y-229043D01*
X580868Y-228965D01*
X580898Y-228884D01*
X580942Y-228802D01*
X580968Y-228762D01*
X580998Y-228725D01*
X581001Y-228721D01*
X581005Y-228717D01*
X581016Y-228706D01*
X581027Y-228695D01*
X581046Y-228677D01*
X581068Y-228662D01*
X581120Y-228621D01*
X581186Y-228580D01*
X581268Y-228543D01*
X581360Y-228510D01*
X581464Y-228488D01*
X581490Y-228802D01*
X581486D01*
X581482Y-228806D01*
X581460Y-228810D01*
X581427Y-228821D01*
X581386Y-228836D01*
X581342Y-228851D01*
X581297Y-228873D01*
X581257Y-228899D01*
X581223Y-228924D01*
X581216Y-228932D01*
X581201Y-228947D01*
X581179Y-228973D01*
X581153Y-229010D01*
X581131Y-229058D01*
X581109Y-229110D01*
X581094Y-229172D01*
X581086Y-229239D01*
Y-229265D01*
X581090Y-229294D01*
X581098Y-229328D01*
X581109Y-229372D01*
X581123Y-229417D01*
X581142Y-229461D01*
X581172Y-229505D01*
X581175Y-229513D01*
X581190Y-229531D01*
X581216Y-229557D01*
X581253Y-229591D01*
X581297Y-229627D01*
X581349Y-229668D01*
X581416Y-229705D01*
X581490Y-229742D01*
X581494D01*
X581501Y-229746D01*
X581512Y-229750D01*
X581527Y-229757D01*
X581549Y-229761D01*
X581575Y-229768D01*
X581604Y-229776D01*
X581641Y-229783D01*
X581682Y-229794D01*
X581727Y-229801D01*
X581775Y-229809D01*
X581826Y-229813D01*
X581886Y-229820D01*
X581945Y-229824D01*
X582012Y-229827D01*
X582078D01*
X582074Y-229824D01*
X582052Y-229809D01*
X582023Y-229783D01*
X581986Y-229750D01*
X581941Y-229713D01*
X581901Y-229664D01*
X581860Y-229613D01*
X581823Y-229554D01*
Y-229550D01*
X581819Y-229546D01*
X581808Y-229524D01*
X581797Y-229491D01*
X581778Y-229446D01*
X581764Y-229394D01*
X581752Y-229335D01*
X581741Y-229272D01*
X581738Y-229206D01*
Y-229176D01*
X581741Y-229154D01*
X581745Y-229124D01*
X581749Y-229095D01*
X581756Y-229058D01*
X581767Y-229021D01*
X581793Y-228936D01*
X581812Y-228891D01*
X581838Y-228847D01*
X581863Y-228802D01*
X581893Y-228754D01*
X581930Y-228710D01*
X581971Y-228669D01*
X581975Y-228665D01*
X581982Y-228658D01*
X581993Y-228647D01*
X582012Y-228636D01*
X582037Y-228617D01*
X582063Y-228599D01*
X582097Y-228580D01*
X582134Y-228558D01*
X582174Y-228536D01*
X582219Y-228518D01*
X582270Y-228499D01*
X582322Y-228481D01*
X582378Y-228469D01*
X582441Y-228458D01*
X582504Y-228451D01*
X582570Y-228447D01*
X582574D01*
X582581D01*
X582592D01*
X582611D01*
X582633Y-228451D01*
D02*
G37*
G36*
X583399Y-230749D02*
X582866Y-231085D01*
X582863D01*
X582855Y-231093D01*
X582844Y-231100D01*
X582829Y-231111D01*
X582789Y-231137D01*
X582737Y-231170D01*
X582681Y-231211D01*
X582622Y-231252D01*
X582566Y-231293D01*
X582515Y-231329D01*
X582511Y-231333D01*
X582496Y-231344D01*
X582474Y-231363D01*
X582448Y-231389D01*
X582393Y-231444D01*
X582367Y-231474D01*
X582344Y-231503D01*
X582341Y-231507D01*
X582337Y-231515D01*
X582330Y-231529D01*
X582319Y-231552D01*
X582307Y-231574D01*
X582296Y-231600D01*
X582278Y-231659D01*
Y-231663D01*
X582274Y-231670D01*
Y-231685D01*
X582270Y-231703D01*
X582267Y-231729D01*
Y-231759D01*
X582263Y-231799D01*
Y-232236D01*
X583399D01*
Y-232576D01*
X580839D01*
Y-231389D01*
X580842Y-231359D01*
Y-231326D01*
X580846Y-231248D01*
X580857Y-231167D01*
X580868Y-231078D01*
X580887Y-230996D01*
X580898Y-230956D01*
X580909Y-230923D01*
Y-230919D01*
X580913Y-230915D01*
X580924Y-230893D01*
X580938Y-230860D01*
X580964Y-230819D01*
X580998Y-230774D01*
X581042Y-230726D01*
X581094Y-230682D01*
X581153Y-230638D01*
X581157D01*
X581160Y-230634D01*
X581183Y-230619D01*
X581220Y-230604D01*
X581268Y-230582D01*
X581323Y-230564D01*
X581390Y-230545D01*
X581460Y-230534D01*
X581538Y-230530D01*
X581542D01*
X581549D01*
X581564D01*
X581582Y-230534D01*
X581608D01*
X581634Y-230538D01*
X581697Y-230553D01*
X581771Y-230575D01*
X581849Y-230604D01*
X581926Y-230649D01*
X581963Y-230678D01*
X582000Y-230708D01*
X582004Y-230712D01*
X582008Y-230715D01*
X582019Y-230726D01*
X582030Y-230741D01*
X582045Y-230760D01*
X582060Y-230782D01*
X582078Y-230812D01*
X582100Y-230841D01*
X582119Y-230878D01*
X582137Y-230919D01*
X582160Y-230963D01*
X582178Y-231011D01*
X582193Y-231067D01*
X582211Y-231122D01*
X582222Y-231185D01*
X582233Y-231252D01*
X582237Y-231244D01*
X582245Y-231230D01*
X582259Y-231207D01*
X582274Y-231178D01*
X582315Y-231111D01*
X582341Y-231078D01*
X582363Y-231048D01*
X582370Y-231041D01*
X582389Y-231022D01*
X582418Y-230993D01*
X582455Y-230956D01*
X582507Y-230915D01*
X582563Y-230867D01*
X582629Y-230819D01*
X582703Y-230767D01*
X583399Y-230327D01*
Y-230749D01*
D02*
G37*
G36*
X583085Y-218194D02*
X583699D01*
Y-218509D01*
X583085D01*
Y-219622D01*
X582796D01*
X581139Y-218450D01*
Y-218194D01*
X582796D01*
Y-217846D01*
X583085D01*
Y-218194D01*
D02*
G37*
G36*
X583699Y-220137D02*
X583166Y-220474D01*
X583163D01*
X583155Y-220481D01*
X583144Y-220488D01*
X583129Y-220499D01*
X583089Y-220525D01*
X583037Y-220559D01*
X582981Y-220599D01*
X582922Y-220640D01*
X582867Y-220681D01*
X582815Y-220718D01*
X582811Y-220721D01*
X582796Y-220732D01*
X582774Y-220751D01*
X582748Y-220777D01*
X582693Y-220832D01*
X582667Y-220862D01*
X582645Y-220892D01*
X582641Y-220895D01*
X582637Y-220903D01*
X582630Y-220918D01*
X582619Y-220940D01*
X582608Y-220962D01*
X582596Y-220988D01*
X582578Y-221047D01*
Y-221051D01*
X582574Y-221058D01*
Y-221073D01*
X582571Y-221091D01*
X582567Y-221117D01*
Y-221147D01*
X582563Y-221188D01*
Y-221624D01*
X583699D01*
Y-221965D01*
X581139D01*
Y-220777D01*
X581142Y-220747D01*
Y-220714D01*
X581146Y-220636D01*
X581157Y-220555D01*
X581168Y-220466D01*
X581187Y-220385D01*
X581198Y-220344D01*
X581209Y-220311D01*
Y-220307D01*
X581213Y-220303D01*
X581224Y-220281D01*
X581239Y-220248D01*
X581264Y-220207D01*
X581298Y-220163D01*
X581342Y-220115D01*
X581394Y-220070D01*
X581453Y-220026D01*
X581457D01*
X581461Y-220022D01*
X581483Y-220007D01*
X581520Y-219992D01*
X581568Y-219970D01*
X581623Y-219952D01*
X581690Y-219933D01*
X581760Y-219922D01*
X581838Y-219918D01*
X581842D01*
X581849D01*
X581864D01*
X581882Y-219922D01*
X581908D01*
X581934Y-219926D01*
X581997Y-219941D01*
X582071Y-219963D01*
X582149Y-219992D01*
X582227Y-220037D01*
X582264Y-220066D01*
X582301Y-220096D01*
X582304Y-220100D01*
X582308Y-220104D01*
X582319Y-220115D01*
X582330Y-220129D01*
X582345Y-220148D01*
X582360Y-220170D01*
X582378Y-220200D01*
X582400Y-220229D01*
X582419Y-220266D01*
X582437Y-220307D01*
X582460Y-220351D01*
X582478Y-220399D01*
X582493Y-220455D01*
X582511Y-220511D01*
X582522Y-220573D01*
X582534Y-220640D01*
X582537Y-220633D01*
X582545Y-220618D01*
X582559Y-220596D01*
X582574Y-220566D01*
X582615Y-220499D01*
X582641Y-220466D01*
X582663Y-220437D01*
X582670Y-220429D01*
X582689Y-220411D01*
X582719Y-220381D01*
X582756Y-220344D01*
X582807Y-220303D01*
X582863Y-220255D01*
X582930Y-220207D01*
X583004Y-220155D01*
X583699Y-219715D01*
Y-220137D01*
D02*
G37*
G36*
X575540Y-208187D02*
X574353D01*
X574323Y-208183D01*
X574290D01*
X574212Y-208179D01*
X574131Y-208168D01*
X574042Y-208157D01*
X573960Y-208138D01*
X573920Y-208127D01*
X573886Y-208116D01*
X573883D01*
X573879Y-208113D01*
X573857Y-208102D01*
X573824Y-208087D01*
X573783Y-208061D01*
X573739Y-208028D01*
X573690Y-207983D01*
X573646Y-207931D01*
X573602Y-207872D01*
Y-207868D01*
X573598Y-207865D01*
X573583Y-207842D01*
X573568Y-207805D01*
X573546Y-207757D01*
X573528Y-207702D01*
X573509Y-207635D01*
X573498Y-207565D01*
X573494Y-207487D01*
Y-207484D01*
Y-207476D01*
Y-207461D01*
X573498Y-207443D01*
Y-207417D01*
X573502Y-207391D01*
X573517Y-207328D01*
X573539Y-207254D01*
X573568Y-207176D01*
X573613Y-207099D01*
X573642Y-207062D01*
X573672Y-207025D01*
X573676Y-207021D01*
X573679Y-207017D01*
X573690Y-207006D01*
X573705Y-206995D01*
X573724Y-206980D01*
X573746Y-206966D01*
X573776Y-206947D01*
X573805Y-206925D01*
X573842Y-206906D01*
X573883Y-206888D01*
X573927Y-206866D01*
X573975Y-206847D01*
X574031Y-206832D01*
X574086Y-206814D01*
X574149Y-206803D01*
X574216Y-206792D01*
X574208Y-206788D01*
X574194Y-206781D01*
X574171Y-206766D01*
X574142Y-206751D01*
X574075Y-206710D01*
X574042Y-206684D01*
X574012Y-206662D01*
X574005Y-206655D01*
X573986Y-206636D01*
X573957Y-206607D01*
X573920Y-206570D01*
X573879Y-206518D01*
X573831Y-206462D01*
X573783Y-206396D01*
X573731Y-206322D01*
X573291Y-205626D01*
X573713D01*
X574049Y-206159D01*
Y-206163D01*
X574057Y-206170D01*
X574064Y-206181D01*
X574075Y-206196D01*
X574101Y-206237D01*
X574134Y-206289D01*
X574175Y-206344D01*
X574216Y-206403D01*
X574257Y-206459D01*
X574294Y-206510D01*
X574297Y-206514D01*
X574308Y-206529D01*
X574327Y-206551D01*
X574353Y-206577D01*
X574408Y-206633D01*
X574438Y-206659D01*
X574468Y-206681D01*
X574471Y-206684D01*
X574478Y-206688D01*
X574493Y-206696D01*
X574515Y-206707D01*
X574538Y-206718D01*
X574564Y-206729D01*
X574623Y-206747D01*
X574627D01*
X574634Y-206751D01*
X574649D01*
X574667Y-206755D01*
X574693Y-206758D01*
X574723D01*
X574763Y-206762D01*
X575200D01*
Y-205626D01*
X575540D01*
Y-208187D01*
D02*
G37*
G36*
X572314Y-205586D02*
X572347Y-205589D01*
X572384Y-205593D01*
X572425Y-205600D01*
X572469Y-205611D01*
X572569Y-205637D01*
X572621Y-205656D01*
X572669Y-205674D01*
X572721Y-205700D01*
X572773Y-205730D01*
X572821Y-205763D01*
X572865Y-205804D01*
X572869Y-205807D01*
X572877Y-205815D01*
X572888Y-205826D01*
X572902Y-205844D01*
X572917Y-205867D01*
X572939Y-205893D01*
X572958Y-205922D01*
X572980Y-205959D01*
X573002Y-205996D01*
X573021Y-206041D01*
X573058Y-206133D01*
X573072Y-206189D01*
X573084Y-206244D01*
X573091Y-206303D01*
X573095Y-206363D01*
Y-206366D01*
Y-206374D01*
Y-206388D01*
X573091Y-206403D01*
Y-206425D01*
X573087Y-206451D01*
X573080Y-206510D01*
X573065Y-206577D01*
X573043Y-206644D01*
X573010Y-206714D01*
X572969Y-206781D01*
Y-206784D01*
X572962Y-206788D01*
X572947Y-206806D01*
X572917Y-206836D01*
X572877Y-206873D01*
X572825Y-206910D01*
X572762Y-206951D01*
X572691Y-206984D01*
X572606Y-207010D01*
X572610D01*
X572614Y-207014D01*
X572625Y-207017D01*
X572640Y-207025D01*
X572673Y-207040D01*
X572717Y-207062D01*
X572765Y-207091D01*
X572814Y-207128D01*
X572858Y-207169D01*
X572899Y-207213D01*
X572902Y-207221D01*
X572914Y-207236D01*
X572928Y-207265D01*
X572943Y-207302D01*
X572962Y-207350D01*
X572976Y-207406D01*
X572987Y-207469D01*
X572991Y-207535D01*
Y-207539D01*
Y-207546D01*
Y-207561D01*
X572987Y-207583D01*
X572984Y-207606D01*
X572980Y-207635D01*
X572965Y-207698D01*
X572943Y-207772D01*
X572906Y-207850D01*
X572884Y-207891D01*
X572858Y-207931D01*
X572825Y-207968D01*
X572791Y-208005D01*
X572788Y-208009D01*
X572780Y-208013D01*
X572769Y-208024D01*
X572754Y-208035D01*
X572736Y-208050D01*
X572710Y-208065D01*
X572680Y-208083D01*
X572651Y-208102D01*
X572614Y-208120D01*
X572573Y-208138D01*
X572529Y-208153D01*
X572481Y-208168D01*
X572377Y-208190D01*
X572318Y-208194D01*
X572259Y-208198D01*
X572225D01*
X572203Y-208194D01*
X572173Y-208190D01*
X572140Y-208187D01*
X572103Y-208183D01*
X572066Y-208172D01*
X571977Y-208150D01*
X571889Y-208116D01*
X571844Y-208094D01*
X571800Y-208068D01*
X571759Y-208035D01*
X571718Y-208002D01*
X571715Y-207998D01*
X571711Y-207994D01*
X571700Y-207983D01*
X571685Y-207968D01*
X571670Y-207946D01*
X571652Y-207924D01*
X571615Y-207868D01*
X571578Y-207798D01*
X571544Y-207717D01*
X571519Y-207624D01*
X571515Y-207576D01*
X571511Y-207524D01*
Y-207521D01*
Y-207517D01*
Y-207495D01*
X571515Y-207461D01*
X571522Y-207421D01*
X571533Y-207369D01*
X571552Y-207317D01*
X571574Y-207265D01*
X571607Y-207213D01*
X571611Y-207206D01*
X571626Y-207191D01*
X571648Y-207169D01*
X571678Y-207139D01*
X571718Y-207106D01*
X571766Y-207073D01*
X571822Y-207040D01*
X571889Y-207010D01*
X571885D01*
X571877Y-207006D01*
X571866Y-207003D01*
X571852Y-206995D01*
X571807Y-206977D01*
X571755Y-206951D01*
X571700Y-206914D01*
X571641Y-206873D01*
X571585Y-206821D01*
X571533Y-206762D01*
Y-206758D01*
X571530Y-206755D01*
X571515Y-206733D01*
X571493Y-206696D01*
X571470Y-206647D01*
X571448Y-206588D01*
X571426Y-206518D01*
X571411Y-206440D01*
X571408Y-206355D01*
Y-206351D01*
Y-206340D01*
Y-206322D01*
X571411Y-206300D01*
X571415Y-206274D01*
X571419Y-206240D01*
X571426Y-206203D01*
X571437Y-206163D01*
X571463Y-206078D01*
X571482Y-206030D01*
X571507Y-205985D01*
X571533Y-205937D01*
X571563Y-205893D01*
X571600Y-205848D01*
X571641Y-205804D01*
X571644Y-205800D01*
X571652Y-205793D01*
X571663Y-205782D01*
X571681Y-205770D01*
X571707Y-205752D01*
X571733Y-205733D01*
X571766Y-205715D01*
X571803Y-205693D01*
X571844Y-205671D01*
X571892Y-205652D01*
X571944Y-205634D01*
X571996Y-205615D01*
X572055Y-205604D01*
X572118Y-205593D01*
X572181Y-205586D01*
X572251Y-205582D01*
X572288D01*
X572314Y-205586D01*
D02*
G37*
G36*
X564577Y-253585D02*
X564610Y-253588D01*
X564651Y-253592D01*
X564692Y-253596D01*
X564740Y-253607D01*
X564840Y-253629D01*
X564951Y-253662D01*
X565006Y-253684D01*
X565058Y-253710D01*
X565110Y-253744D01*
X565162Y-253777D01*
X565166Y-253781D01*
X565173Y-253784D01*
X565188Y-253796D01*
X565206Y-253814D01*
X565225Y-253833D01*
X565251Y-253858D01*
X565276Y-253888D01*
X565306Y-253918D01*
X565336Y-253955D01*
X565365Y-253999D01*
X565399Y-254043D01*
X565428Y-254092D01*
X565454Y-254147D01*
X565484Y-254203D01*
X565506Y-254262D01*
X565528Y-254328D01*
X565195Y-254406D01*
Y-254402D01*
X565191Y-254395D01*
X565184Y-254380D01*
X565177Y-254362D01*
X565169Y-254339D01*
X565158Y-254310D01*
X565129Y-254251D01*
X565092Y-254184D01*
X565047Y-254117D01*
X564992Y-254054D01*
X564932Y-253999D01*
X564925Y-253992D01*
X564903Y-253977D01*
X564866Y-253958D01*
X564818Y-253932D01*
X564755Y-253910D01*
X564684Y-253888D01*
X564599Y-253873D01*
X564507Y-253870D01*
X564477D01*
X564459Y-253873D01*
X564433D01*
X564403Y-253877D01*
X564333Y-253888D01*
X564255Y-253903D01*
X564174Y-253929D01*
X564089Y-253966D01*
X564011Y-254014D01*
X564007D01*
X564004Y-254021D01*
X563978Y-254040D01*
X563944Y-254069D01*
X563904Y-254114D01*
X563856Y-254169D01*
X563811Y-254232D01*
X563771Y-254310D01*
X563734Y-254395D01*
Y-254399D01*
X563730Y-254406D01*
X563726Y-254417D01*
X563723Y-254436D01*
X563715Y-254458D01*
X563708Y-254484D01*
X563697Y-254547D01*
X563682Y-254621D01*
X563667Y-254702D01*
X563660Y-254791D01*
X563656Y-254887D01*
Y-254891D01*
Y-254902D01*
Y-254920D01*
Y-254942D01*
X563660Y-254968D01*
Y-255002D01*
X563663Y-255039D01*
X563667Y-255079D01*
X563678Y-255168D01*
X563697Y-255264D01*
X563719Y-255361D01*
X563748Y-255457D01*
Y-255461D01*
X563752Y-255468D01*
X563760Y-255479D01*
X563767Y-255498D01*
X563789Y-255542D01*
X563822Y-255594D01*
X563863Y-255653D01*
X563915Y-255716D01*
X563974Y-255771D01*
X564044Y-255823D01*
X564048D01*
X564055Y-255827D01*
X564067Y-255834D01*
X564081Y-255842D01*
X564100Y-255849D01*
X564122Y-255860D01*
X564174Y-255882D01*
X564241Y-255905D01*
X564315Y-255923D01*
X564396Y-255938D01*
X564481Y-255942D01*
X564507D01*
X564529Y-255938D01*
X564555D01*
X564581Y-255934D01*
X564647Y-255919D01*
X564725Y-255901D01*
X564803Y-255871D01*
X564884Y-255831D01*
X564925Y-255808D01*
X564962Y-255779D01*
X564966Y-255775D01*
X564969Y-255771D01*
X564981Y-255760D01*
X564995Y-255749D01*
X565010Y-255731D01*
X565029Y-255708D01*
X565051Y-255686D01*
X565069Y-255657D01*
X565092Y-255623D01*
X565117Y-255586D01*
X565140Y-255549D01*
X565162Y-255505D01*
X565180Y-255457D01*
X565199Y-255405D01*
X565217Y-255349D01*
X565232Y-255290D01*
X565573Y-255375D01*
Y-255379D01*
X565569Y-255394D01*
X565561Y-255416D01*
X565550Y-255446D01*
X565539Y-255479D01*
X565524Y-255520D01*
X565506Y-255564D01*
X565484Y-255612D01*
X565432Y-255716D01*
X565365Y-255819D01*
X565325Y-255871D01*
X565284Y-255923D01*
X565239Y-255967D01*
X565188Y-256012D01*
X565184Y-256015D01*
X565177Y-256023D01*
X565158Y-256030D01*
X565140Y-256045D01*
X565110Y-256064D01*
X565080Y-256082D01*
X565040Y-256101D01*
X564999Y-256119D01*
X564951Y-256141D01*
X564899Y-256160D01*
X564844Y-256178D01*
X564784Y-256197D01*
X564721Y-256212D01*
X564655Y-256219D01*
X564585Y-256226D01*
X564511Y-256230D01*
X564470D01*
X564440Y-256226D01*
X564407D01*
X564366Y-256223D01*
X564322Y-256215D01*
X564270Y-256208D01*
X564163Y-256189D01*
X564052Y-256160D01*
X563941Y-256119D01*
X563889Y-256093D01*
X563837Y-256064D01*
X563834Y-256060D01*
X563826Y-256056D01*
X563811Y-256045D01*
X563797Y-256030D01*
X563774Y-256015D01*
X563748Y-255993D01*
X563719Y-255967D01*
X563689Y-255938D01*
X563660Y-255905D01*
X563626Y-255871D01*
X563560Y-255786D01*
X563497Y-255686D01*
X563441Y-255575D01*
Y-255572D01*
X563434Y-255560D01*
X563430Y-255542D01*
X563419Y-255520D01*
X563412Y-255490D01*
X563401Y-255453D01*
X563386Y-255412D01*
X563375Y-255368D01*
X563364Y-255320D01*
X563349Y-255264D01*
X563330Y-255150D01*
X563315Y-255020D01*
X563308Y-254887D01*
Y-254883D01*
Y-254869D01*
Y-254846D01*
X563312Y-254820D01*
Y-254783D01*
X563315Y-254746D01*
X563319Y-254698D01*
X563327Y-254650D01*
X563345Y-254543D01*
X563371Y-254425D01*
X563408Y-254306D01*
X563460Y-254191D01*
X563463Y-254188D01*
X563467Y-254177D01*
X563475Y-254162D01*
X563489Y-254143D01*
X563504Y-254117D01*
X563523Y-254088D01*
X563571Y-254021D01*
X563634Y-253947D01*
X563708Y-253873D01*
X563793Y-253799D01*
X563893Y-253736D01*
X563896Y-253733D01*
X563907Y-253729D01*
X563922Y-253721D01*
X563941Y-253710D01*
X563970Y-253699D01*
X564000Y-253688D01*
X564037Y-253673D01*
X564078Y-253659D01*
X564122Y-253644D01*
X564170Y-253629D01*
X564274Y-253607D01*
X564392Y-253588D01*
X564514Y-253581D01*
X564551D01*
X564577Y-253585D01*
D02*
G37*
G36*
X567182Y-255283D02*
X567530D01*
Y-255572D01*
X567182D01*
Y-256186D01*
X566867D01*
Y-255572D01*
X565754D01*
Y-255283D01*
X566927Y-253625D01*
X567182D01*
Y-255283D01*
D02*
G37*
G36*
X600449Y-276180D02*
X600108D01*
Y-273923D01*
X598847D01*
Y-273620D01*
X600449D01*
Y-276180D01*
D02*
G37*
G36*
X597703Y-275622D02*
X597707Y-275618D01*
X597726Y-275603D01*
X597748Y-275581D01*
X597785Y-275555D01*
X597826Y-275522D01*
X597877Y-275485D01*
X597936Y-275444D01*
X598003Y-275403D01*
X598007D01*
X598010Y-275399D01*
X598033Y-275385D01*
X598070Y-275366D01*
X598114Y-275344D01*
X598166Y-275318D01*
X598221Y-275292D01*
X598277Y-275266D01*
X598332Y-275244D01*
Y-275548D01*
X598329D01*
X598321Y-275555D01*
X598307Y-275559D01*
X598288Y-275570D01*
X598266Y-275581D01*
X598240Y-275596D01*
X598177Y-275633D01*
X598103Y-275673D01*
X598029Y-275725D01*
X597951Y-275784D01*
X597874Y-275847D01*
X597870Y-275851D01*
X597866Y-275855D01*
X597855Y-275866D01*
X597840Y-275877D01*
X597807Y-275914D01*
X597763Y-275958D01*
X597718Y-276010D01*
X597670Y-276069D01*
X597629Y-276128D01*
X597592Y-276191D01*
X597389D01*
Y-273620D01*
X597703D01*
Y-275622D01*
D02*
G37*
G36*
X657597Y-175156D02*
X657623Y-175160D01*
X657656Y-175164D01*
X657693Y-175171D01*
X657734Y-175182D01*
X657819Y-175208D01*
X657867Y-175227D01*
X657911Y-175252D01*
X657959Y-175278D01*
X658004Y-175308D01*
X658048Y-175345D01*
X658093Y-175386D01*
X658096Y-175389D01*
X658104Y-175397D01*
X658115Y-175408D01*
X658126Y-175426D01*
X658144Y-175452D01*
X658163Y-175478D01*
X658181Y-175512D01*
X658204Y-175549D01*
X658226Y-175589D01*
X658244Y-175637D01*
X658263Y-175689D01*
X658281Y-175741D01*
X658292Y-175800D01*
X658303Y-175863D01*
X658311Y-175926D01*
X658315Y-175996D01*
Y-176033D01*
X658311Y-176059D01*
X658307Y-176092D01*
X658303Y-176129D01*
X658296Y-176170D01*
X658285Y-176215D01*
X658259Y-176314D01*
X658241Y-176366D01*
X658222Y-176414D01*
X658196Y-176466D01*
X658167Y-176518D01*
X658133Y-176566D01*
X658093Y-176610D01*
X658089Y-176614D01*
X658081Y-176621D01*
X658070Y-176633D01*
X658052Y-176647D01*
X658030Y-176662D01*
X658004Y-176684D01*
X657974Y-176703D01*
X657937Y-176725D01*
X657900Y-176747D01*
X657856Y-176766D01*
X657763Y-176803D01*
X657708Y-176818D01*
X657652Y-176829D01*
X657593Y-176836D01*
X657534Y-176840D01*
X657530D01*
X657523D01*
X657508D01*
X657493Y-176836D01*
X657471D01*
X657445Y-176832D01*
X657386Y-176825D01*
X657319Y-176810D01*
X657253Y-176788D01*
X657182Y-176755D01*
X657116Y-176714D01*
X657112D01*
X657108Y-176707D01*
X657090Y-176692D01*
X657060Y-176662D01*
X657023Y-176621D01*
X656986Y-176570D01*
X656946Y-176507D01*
X656912Y-176436D01*
X656886Y-176351D01*
Y-176355D01*
X656883Y-176359D01*
X656879Y-176370D01*
X656872Y-176385D01*
X656857Y-176418D01*
X656835Y-176462D01*
X656805Y-176511D01*
X656768Y-176559D01*
X656727Y-176603D01*
X656683Y-176644D01*
X656675Y-176647D01*
X656661Y-176658D01*
X656631Y-176673D01*
X656594Y-176688D01*
X656546Y-176707D01*
X656491Y-176721D01*
X656428Y-176733D01*
X656361Y-176736D01*
X656357D01*
X656350D01*
X656335D01*
X656313Y-176733D01*
X656291Y-176729D01*
X656261Y-176725D01*
X656198Y-176710D01*
X656124Y-176688D01*
X656046Y-176651D01*
X656006Y-176629D01*
X655965Y-176603D01*
X655928Y-176570D01*
X655891Y-176536D01*
X655887Y-176533D01*
X655884Y-176525D01*
X655873Y-176514D01*
X655862Y-176499D01*
X655847Y-176481D01*
X655832Y-176455D01*
X655813Y-176425D01*
X655795Y-176396D01*
X655776Y-176359D01*
X655758Y-176318D01*
X655743Y-176274D01*
X655728Y-176226D01*
X655706Y-176122D01*
X655702Y-176063D01*
X655699Y-176004D01*
Y-175970D01*
X655702Y-175948D01*
X655706Y-175918D01*
X655710Y-175885D01*
X655714Y-175848D01*
X655725Y-175811D01*
X655747Y-175722D01*
X655780Y-175634D01*
X655802Y-175589D01*
X655828Y-175545D01*
X655862Y-175504D01*
X655895Y-175463D01*
X655899Y-175460D01*
X655902Y-175456D01*
X655913Y-175445D01*
X655928Y-175430D01*
X655950Y-175415D01*
X655972Y-175397D01*
X656028Y-175360D01*
X656098Y-175323D01*
X656180Y-175289D01*
X656272Y-175264D01*
X656320Y-175260D01*
X656372Y-175256D01*
X656376D01*
X656380D01*
X656402D01*
X656435Y-175260D01*
X656476Y-175267D01*
X656528Y-175278D01*
X656579Y-175297D01*
X656631Y-175319D01*
X656683Y-175352D01*
X656690Y-175356D01*
X656705Y-175371D01*
X656727Y-175393D01*
X656757Y-175423D01*
X656790Y-175463D01*
X656823Y-175512D01*
X656857Y-175567D01*
X656886Y-175634D01*
Y-175630D01*
X656890Y-175622D01*
X656894Y-175611D01*
X656901Y-175597D01*
X656920Y-175552D01*
X656946Y-175500D01*
X656983Y-175445D01*
X657023Y-175386D01*
X657075Y-175330D01*
X657134Y-175278D01*
X657138D01*
X657142Y-175275D01*
X657164Y-175260D01*
X657201Y-175238D01*
X657249Y-175215D01*
X657308Y-175193D01*
X657378Y-175171D01*
X657456Y-175156D01*
X657541Y-175153D01*
X657545D01*
X657556D01*
X657575D01*
X657597Y-175156D01*
D02*
G37*
G36*
X657571Y-177151D02*
X657600Y-177154D01*
X657634Y-177162D01*
X657671Y-177169D01*
X657712Y-177176D01*
X657800Y-177206D01*
X657848Y-177228D01*
X657893Y-177251D01*
X657941Y-177280D01*
X657989Y-177313D01*
X658037Y-177350D01*
X658081Y-177395D01*
X658085Y-177399D01*
X658093Y-177406D01*
X658104Y-177421D01*
X658118Y-177439D01*
X658137Y-177461D01*
X658155Y-177491D01*
X658178Y-177524D01*
X658196Y-177565D01*
X658218Y-177606D01*
X658241Y-177654D01*
X658259Y-177702D01*
X658278Y-177757D01*
X658292Y-177817D01*
X658303Y-177880D01*
X658311Y-177942D01*
X658315Y-178013D01*
Y-178046D01*
X658311Y-178068D01*
X658307Y-178098D01*
X658303Y-178131D01*
X658296Y-178168D01*
X658289Y-178209D01*
X658266Y-178298D01*
X658229Y-178390D01*
X658207Y-178438D01*
X658181Y-178483D01*
X658148Y-178527D01*
X658115Y-178571D01*
X658111Y-178575D01*
X658104Y-178583D01*
X658093Y-178594D01*
X658078Y-178605D01*
X658059Y-178623D01*
X658033Y-178642D01*
X658007Y-178664D01*
X657974Y-178686D01*
X657937Y-178708D01*
X657900Y-178730D01*
X657811Y-178771D01*
X657708Y-178805D01*
X657652Y-178816D01*
X657593Y-178823D01*
X657552Y-178508D01*
X657556D01*
X657563Y-178505D01*
X657578Y-178501D01*
X657597Y-178497D01*
X657619Y-178494D01*
X657645Y-178486D01*
X657700Y-178468D01*
X657767Y-178442D01*
X657830Y-178409D01*
X657889Y-178372D01*
X657941Y-178327D01*
X657945Y-178320D01*
X657959Y-178305D01*
X657978Y-178275D01*
X657996Y-178238D01*
X658019Y-178194D01*
X658037Y-178138D01*
X658052Y-178076D01*
X658056Y-178009D01*
Y-177987D01*
X658052Y-177972D01*
X658048Y-177931D01*
X658037Y-177880D01*
X658019Y-177820D01*
X657993Y-177757D01*
X657956Y-177694D01*
X657904Y-177635D01*
X657897Y-177628D01*
X657874Y-177609D01*
X657841Y-177587D01*
X657797Y-177558D01*
X657741Y-177528D01*
X657678Y-177506D01*
X657604Y-177487D01*
X657523Y-177480D01*
X657519D01*
X657512D01*
X657501D01*
X657486Y-177484D01*
X657445Y-177487D01*
X657397Y-177498D01*
X657338Y-177513D01*
X657279Y-177539D01*
X657219Y-177576D01*
X657164Y-177624D01*
X657157Y-177632D01*
X657142Y-177650D01*
X657120Y-177680D01*
X657094Y-177720D01*
X657068Y-177772D01*
X657046Y-177835D01*
X657031Y-177905D01*
X657023Y-177983D01*
Y-178016D01*
X657027Y-178042D01*
X657031Y-178076D01*
X657038Y-178113D01*
X657046Y-178157D01*
X657057Y-178205D01*
X656779Y-178168D01*
Y-178150D01*
X656783Y-178135D01*
Y-178087D01*
X656775Y-178046D01*
X656768Y-177998D01*
X656757Y-177942D01*
X656738Y-177880D01*
X656712Y-177820D01*
X656679Y-177757D01*
Y-177754D01*
X656675Y-177750D01*
X656661Y-177732D01*
X656635Y-177706D01*
X656601Y-177676D01*
X656553Y-177646D01*
X656498Y-177620D01*
X656435Y-177602D01*
X656398Y-177595D01*
X656357D01*
X656354D01*
X656350D01*
X656328D01*
X656298Y-177602D01*
X656257Y-177609D01*
X656213Y-177624D01*
X656165Y-177643D01*
X656117Y-177672D01*
X656072Y-177713D01*
X656069Y-177717D01*
X656054Y-177735D01*
X656035Y-177761D01*
X656013Y-177794D01*
X655995Y-177839D01*
X655976Y-177891D01*
X655961Y-177950D01*
X655958Y-178016D01*
Y-178046D01*
X655965Y-178079D01*
X655972Y-178124D01*
X655987Y-178172D01*
X656006Y-178220D01*
X656035Y-178272D01*
X656072Y-178320D01*
X656076Y-178323D01*
X656095Y-178338D01*
X656120Y-178360D01*
X656157Y-178386D01*
X656206Y-178412D01*
X656265Y-178438D01*
X656335Y-178460D01*
X656417Y-178475D01*
X656361Y-178790D01*
X656357D01*
X656346Y-178786D01*
X656331Y-178782D01*
X656309Y-178779D01*
X656283Y-178771D01*
X656254Y-178760D01*
X656183Y-178738D01*
X656102Y-178701D01*
X656021Y-178656D01*
X655943Y-178601D01*
X655873Y-178531D01*
X655869Y-178527D01*
X655865Y-178520D01*
X655858Y-178508D01*
X655847Y-178494D01*
X655832Y-178475D01*
X655817Y-178449D01*
X655802Y-178423D01*
X655784Y-178390D01*
X655754Y-178316D01*
X655725Y-178231D01*
X655706Y-178131D01*
X655699Y-178079D01*
Y-177987D01*
X655702Y-177946D01*
X655710Y-177898D01*
X655721Y-177839D01*
X655739Y-177772D01*
X655762Y-177706D01*
X655791Y-177639D01*
Y-177635D01*
X655795Y-177632D01*
X655806Y-177609D01*
X655828Y-177576D01*
X655854Y-177539D01*
X655891Y-177495D01*
X655932Y-177450D01*
X655980Y-177406D01*
X656035Y-177369D01*
X656043Y-177365D01*
X656061Y-177354D01*
X656095Y-177339D01*
X656135Y-177321D01*
X656183Y-177302D01*
X656239Y-177287D01*
X656302Y-177276D01*
X656365Y-177273D01*
X656372D01*
X656394D01*
X656424Y-177276D01*
X656465Y-177284D01*
X656513Y-177295D01*
X656565Y-177313D01*
X656616Y-177336D01*
X656668Y-177365D01*
X656675Y-177369D01*
X656690Y-177380D01*
X656716Y-177402D01*
X656746Y-177432D01*
X656779Y-177469D01*
X656816Y-177513D01*
X656849Y-177565D01*
X656883Y-177628D01*
Y-177624D01*
X656886Y-177617D01*
X656890Y-177606D01*
X656894Y-177591D01*
X656909Y-177550D01*
X656931Y-177498D01*
X656960Y-177439D01*
X656997Y-177380D01*
X657046Y-177324D01*
X657101Y-177273D01*
X657108Y-177269D01*
X657131Y-177254D01*
X657168Y-177232D01*
X657216Y-177210D01*
X657275Y-177188D01*
X657345Y-177165D01*
X657427Y-177151D01*
X657515Y-177147D01*
X657519D01*
X657530D01*
X657549D01*
X657571Y-177151D01*
D02*
G37*
G36*
X657538Y-179256D02*
X657567D01*
X657638Y-179263D01*
X657719Y-179271D01*
X657804Y-179286D01*
X657882Y-179308D01*
X657956Y-179334D01*
X657959D01*
X657963Y-179337D01*
X657985Y-179348D01*
X658015Y-179367D01*
X658056Y-179393D01*
X658096Y-179430D01*
X658141Y-179471D01*
X658185Y-179522D01*
X658222Y-179581D01*
X658226Y-179589D01*
X658237Y-179611D01*
X658252Y-179644D01*
X658266Y-179692D01*
X658285Y-179752D01*
X658300Y-179818D01*
X658311Y-179892D01*
X658315Y-179974D01*
Y-180007D01*
X658311Y-180029D01*
X658307Y-180059D01*
X658303Y-180088D01*
X658289Y-180166D01*
X658266Y-180247D01*
X658233Y-180333D01*
X658211Y-180377D01*
X658185Y-180418D01*
X658155Y-180455D01*
X658122Y-180492D01*
X658118Y-180495D01*
X658115Y-180499D01*
X658100Y-180507D01*
X658085Y-180518D01*
X658067Y-180532D01*
X658041Y-180547D01*
X658011Y-180562D01*
X657978Y-180580D01*
X657941Y-180595D01*
X657897Y-180610D01*
X657852Y-180625D01*
X657800Y-180640D01*
X657745Y-180647D01*
X657682Y-180658D01*
X657619Y-180662D01*
X657549D01*
X657504Y-180355D01*
X657508D01*
X657515D01*
X657530D01*
X657552Y-180351D01*
X657575Y-180347D01*
X657600D01*
X657663Y-180336D01*
X657730Y-180325D01*
X657797Y-180303D01*
X657856Y-180281D01*
X657882Y-180266D01*
X657904Y-180247D01*
X657908Y-180244D01*
X657919Y-180229D01*
X657937Y-180207D01*
X657956Y-180177D01*
X657978Y-180137D01*
X657993Y-180092D01*
X658007Y-180037D01*
X658011Y-179977D01*
Y-179955D01*
X658007Y-179933D01*
X658004Y-179900D01*
X657996Y-179866D01*
X657989Y-179829D01*
X657974Y-179792D01*
X657956Y-179755D01*
X657952Y-179752D01*
X657945Y-179741D01*
X657930Y-179726D01*
X657915Y-179704D01*
X657889Y-179685D01*
X657863Y-179663D01*
X657834Y-179644D01*
X657797Y-179630D01*
X657793D01*
X657778Y-179622D01*
X657752Y-179619D01*
X657719Y-179611D01*
X657675Y-179604D01*
X657619Y-179600D01*
X657552Y-179593D01*
X657475D01*
X655710D01*
Y-179252D01*
X657456D01*
X657460D01*
X657471D01*
X657486D01*
X657508D01*
X657538Y-179256D01*
D02*
G37*
G36*
X603109Y-331928D02*
Y-331931D01*
Y-331946D01*
Y-331965D01*
Y-331991D01*
X603105Y-332024D01*
Y-332061D01*
X603102Y-332105D01*
X603098Y-332150D01*
X603087Y-332249D01*
X603072Y-332353D01*
X603050Y-332453D01*
X603035Y-332501D01*
X603020Y-332545D01*
Y-332549D01*
X603017Y-332557D01*
X603009Y-332568D01*
X603002Y-332582D01*
X602980Y-332623D01*
X602946Y-332675D01*
X602902Y-332734D01*
X602850Y-332793D01*
X602783Y-332856D01*
X602702Y-332912D01*
X602698D01*
X602691Y-332919D01*
X602680Y-332923D01*
X602661Y-332934D01*
X602639Y-332945D01*
X602609Y-332956D01*
X602580Y-332967D01*
X602543Y-332982D01*
X602502Y-332997D01*
X602458Y-333008D01*
X602410Y-333019D01*
X602354Y-333030D01*
X602299Y-333038D01*
X602240Y-333045D01*
X602106Y-333052D01*
X602073D01*
X602047Y-333049D01*
X602017D01*
X601980Y-333045D01*
X601940Y-333041D01*
X601899Y-333038D01*
X601807Y-333023D01*
X601707Y-333001D01*
X601611Y-332971D01*
X601518Y-332930D01*
X601514D01*
X601507Y-332923D01*
X601496Y-332915D01*
X601481Y-332908D01*
X601440Y-332878D01*
X601392Y-332838D01*
X601337Y-332786D01*
X601285Y-332727D01*
X601233Y-332653D01*
X601192Y-332571D01*
Y-332568D01*
X601189Y-332560D01*
X601185Y-332545D01*
X601178Y-332527D01*
X601170Y-332505D01*
X601163Y-332475D01*
X601152Y-332442D01*
X601144Y-332401D01*
X601137Y-332357D01*
X601126Y-332309D01*
X601118Y-332257D01*
X601111Y-332201D01*
X601104Y-332138D01*
X601100Y-332072D01*
X601096Y-332002D01*
Y-331928D01*
Y-330448D01*
X601437D01*
Y-331928D01*
Y-331931D01*
Y-331942D01*
Y-331961D01*
Y-331983D01*
X601440Y-332009D01*
Y-332042D01*
X601444Y-332113D01*
X601451Y-332194D01*
X601463Y-332275D01*
X601477Y-332353D01*
X601485Y-332386D01*
X601496Y-332420D01*
X601500Y-332427D01*
X601507Y-332446D01*
X601525Y-332471D01*
X601548Y-332508D01*
X601574Y-332545D01*
X601611Y-332586D01*
X601655Y-332627D01*
X601707Y-332660D01*
X601714Y-332664D01*
X601733Y-332675D01*
X601766Y-332686D01*
X601810Y-332701D01*
X601862Y-332719D01*
X601929Y-332731D01*
X601999Y-332742D01*
X602077Y-332745D01*
X602114D01*
X602136Y-332742D01*
X602169D01*
X602203Y-332738D01*
X602284Y-332723D01*
X602373Y-332705D01*
X602458Y-332675D01*
X602539Y-332634D01*
X602576Y-332608D01*
X602609Y-332579D01*
X602613Y-332575D01*
X602617Y-332571D01*
X602624Y-332560D01*
X602635Y-332545D01*
X602646Y-332523D01*
X602661Y-332501D01*
X602676Y-332468D01*
X602691Y-332435D01*
X602706Y-332394D01*
X602717Y-332346D01*
X602732Y-332290D01*
X602743Y-332231D01*
X602754Y-332164D01*
X602761Y-332094D01*
X602769Y-332013D01*
Y-331928D01*
Y-330448D01*
X603109D01*
Y-331928D01*
D02*
G37*
G36*
X605122Y-330781D02*
X604097D01*
X603960Y-331472D01*
X603964Y-331469D01*
X603971Y-331465D01*
X603982Y-331458D01*
X604001Y-331447D01*
X604023Y-331435D01*
X604049Y-331421D01*
X604108Y-331391D01*
X604182Y-331362D01*
X604263Y-331336D01*
X604352Y-331317D01*
X604397Y-331310D01*
X604478D01*
X604500Y-331313D01*
X604530Y-331317D01*
X604563Y-331321D01*
X604600Y-331328D01*
X604641Y-331339D01*
X604730Y-331365D01*
X604778Y-331384D01*
X604826Y-331410D01*
X604874Y-331435D01*
X604922Y-331465D01*
X604966Y-331502D01*
X605011Y-331543D01*
X605015Y-331546D01*
X605022Y-331554D01*
X605033Y-331565D01*
X605048Y-331583D01*
X605066Y-331609D01*
X605085Y-331635D01*
X605107Y-331669D01*
X605129Y-331706D01*
X605148Y-331746D01*
X605170Y-331791D01*
X605188Y-331842D01*
X605207Y-331894D01*
X605222Y-331950D01*
X605233Y-332013D01*
X605240Y-332076D01*
X605244Y-332142D01*
Y-332146D01*
Y-332157D01*
Y-332175D01*
X605240Y-332201D01*
X605236Y-332231D01*
X605233Y-332264D01*
X605225Y-332305D01*
X605218Y-332346D01*
X605196Y-332442D01*
X605159Y-332542D01*
X605137Y-332594D01*
X605107Y-332642D01*
X605077Y-332694D01*
X605040Y-332742D01*
X605037Y-332745D01*
X605029Y-332756D01*
X605015Y-332771D01*
X604996Y-332790D01*
X604970Y-332812D01*
X604941Y-332841D01*
X604904Y-332867D01*
X604863Y-332897D01*
X604818Y-332927D01*
X604767Y-332952D01*
X604711Y-332978D01*
X604652Y-333004D01*
X604589Y-333023D01*
X604519Y-333038D01*
X604445Y-333049D01*
X604367Y-333052D01*
X604334D01*
X604308Y-333049D01*
X604278Y-333045D01*
X604245Y-333041D01*
X604204Y-333038D01*
X604164Y-333027D01*
X604071Y-333004D01*
X603978Y-332971D01*
X603930Y-332949D01*
X603882Y-332923D01*
X603838Y-332893D01*
X603793Y-332860D01*
X603790Y-332856D01*
X603782Y-332853D01*
X603775Y-332838D01*
X603760Y-332823D01*
X603742Y-332804D01*
X603723Y-332782D01*
X603701Y-332753D01*
X603683Y-332719D01*
X603660Y-332686D01*
X603638Y-332645D01*
X603597Y-332557D01*
X603564Y-332453D01*
X603553Y-332398D01*
X603546Y-332338D01*
X603875Y-332312D01*
Y-332316D01*
Y-332324D01*
X603879Y-332335D01*
X603882Y-332353D01*
X603893Y-332394D01*
X603908Y-332449D01*
X603930Y-332505D01*
X603960Y-332568D01*
X603997Y-332623D01*
X604041Y-332675D01*
X604049Y-332679D01*
X604064Y-332694D01*
X604093Y-332712D01*
X604134Y-332734D01*
X604178Y-332756D01*
X604234Y-332775D01*
X604297Y-332790D01*
X604367Y-332793D01*
X604389D01*
X604404Y-332790D01*
X604448Y-332786D01*
X604500Y-332771D01*
X604563Y-332753D01*
X604626Y-332723D01*
X604693Y-332679D01*
X604722Y-332653D01*
X604752Y-332623D01*
X604755Y-332620D01*
X604759Y-332616D01*
X604767Y-332605D01*
X604778Y-332594D01*
X604804Y-332553D01*
X604833Y-332501D01*
X604859Y-332438D01*
X604885Y-332361D01*
X604904Y-332268D01*
X604911Y-332220D01*
Y-332168D01*
Y-332164D01*
Y-332157D01*
Y-332142D01*
X604907Y-332124D01*
Y-332101D01*
X604904Y-332076D01*
X604892Y-332016D01*
X604874Y-331946D01*
X604848Y-331876D01*
X604811Y-331809D01*
X604759Y-331746D01*
Y-331743D01*
X604752Y-331739D01*
X604733Y-331720D01*
X604700Y-331695D01*
X604656Y-331665D01*
X604596Y-331639D01*
X604530Y-331613D01*
X604452Y-331595D01*
X604408Y-331587D01*
X604337D01*
X604308Y-331591D01*
X604271Y-331595D01*
X604226Y-331606D01*
X604182Y-331617D01*
X604134Y-331635D01*
X604086Y-331658D01*
X604082Y-331661D01*
X604067Y-331669D01*
X604045Y-331687D01*
X604015Y-331706D01*
X603986Y-331732D01*
X603956Y-331765D01*
X603923Y-331798D01*
X603897Y-331839D01*
X603601Y-331798D01*
X603849Y-330481D01*
X605122D01*
Y-330781D01*
D02*
G37*
G36*
X521581Y-330768D02*
X520556D01*
X520419Y-331460D01*
X520423Y-331457D01*
X520430Y-331453D01*
X520441Y-331446D01*
X520460Y-331434D01*
X520482Y-331423D01*
X520508Y-331409D01*
X520567Y-331379D01*
X520641Y-331349D01*
X520722Y-331324D01*
X520811Y-331305D01*
X520855Y-331298D01*
X520937D01*
X520959Y-331301D01*
X520989Y-331305D01*
X521022Y-331309D01*
X521059Y-331316D01*
X521100Y-331327D01*
X521188Y-331353D01*
X521237Y-331372D01*
X521285Y-331398D01*
X521333Y-331423D01*
X521381Y-331453D01*
X521425Y-331490D01*
X521470Y-331531D01*
X521473Y-331534D01*
X521481Y-331542D01*
X521492Y-331553D01*
X521507Y-331571D01*
X521525Y-331597D01*
X521544Y-331623D01*
X521566Y-331657D01*
X521588Y-331694D01*
X521606Y-331734D01*
X521629Y-331779D01*
X521647Y-331830D01*
X521666Y-331882D01*
X521680Y-331938D01*
X521692Y-332001D01*
X521699Y-332064D01*
X521703Y-332130D01*
Y-332134D01*
Y-332145D01*
Y-332163D01*
X521699Y-332189D01*
X521695Y-332219D01*
X521692Y-332252D01*
X521684Y-332293D01*
X521677Y-332334D01*
X521655Y-332430D01*
X521618Y-332530D01*
X521595Y-332581D01*
X521566Y-332630D01*
X521536Y-332681D01*
X521499Y-332730D01*
X521495Y-332733D01*
X521488Y-332744D01*
X521473Y-332759D01*
X521455Y-332778D01*
X521429Y-332800D01*
X521399Y-332829D01*
X521362Y-332855D01*
X521322Y-332885D01*
X521277Y-332914D01*
X521225Y-332940D01*
X521170Y-332966D01*
X521111Y-332992D01*
X521048Y-333011D01*
X520977Y-333026D01*
X520903Y-333037D01*
X520826Y-333040D01*
X520792D01*
X520767Y-333037D01*
X520737Y-333033D01*
X520704Y-333029D01*
X520663Y-333026D01*
X520622Y-333014D01*
X520530Y-332992D01*
X520437Y-332959D01*
X520389Y-332937D01*
X520341Y-332911D01*
X520297Y-332881D01*
X520252Y-332848D01*
X520249Y-332844D01*
X520241Y-332840D01*
X520234Y-332826D01*
X520219Y-332811D01*
X520200Y-332792D01*
X520182Y-332770D01*
X520160Y-332741D01*
X520141Y-332707D01*
X520119Y-332674D01*
X520097Y-332633D01*
X520056Y-332544D01*
X520023Y-332441D01*
X520012Y-332385D01*
X520004Y-332326D01*
X520334Y-332300D01*
Y-332304D01*
Y-332311D01*
X520337Y-332323D01*
X520341Y-332341D01*
X520352Y-332382D01*
X520367Y-332437D01*
X520389Y-332493D01*
X520419Y-332556D01*
X520456Y-332611D01*
X520500Y-332663D01*
X520508Y-332667D01*
X520522Y-332681D01*
X520552Y-332700D01*
X520593Y-332722D01*
X520637Y-332744D01*
X520693Y-332763D01*
X520755Y-332778D01*
X520826Y-332781D01*
X520848D01*
X520863Y-332778D01*
X520907Y-332774D01*
X520959Y-332759D01*
X521022Y-332741D01*
X521085Y-332711D01*
X521151Y-332667D01*
X521181Y-332641D01*
X521211Y-332611D01*
X521214Y-332607D01*
X521218Y-332604D01*
X521225Y-332593D01*
X521237Y-332581D01*
X521262Y-332541D01*
X521292Y-332489D01*
X521318Y-332426D01*
X521344Y-332348D01*
X521362Y-332256D01*
X521370Y-332208D01*
Y-332156D01*
Y-332152D01*
Y-332145D01*
Y-332130D01*
X521366Y-332112D01*
Y-332089D01*
X521362Y-332064D01*
X521351Y-332004D01*
X521333Y-331934D01*
X521307Y-331864D01*
X521270Y-331797D01*
X521218Y-331734D01*
Y-331731D01*
X521211Y-331727D01*
X521192Y-331708D01*
X521159Y-331682D01*
X521114Y-331653D01*
X521055Y-331627D01*
X520989Y-331601D01*
X520911Y-331582D01*
X520866Y-331575D01*
X520796D01*
X520767Y-331579D01*
X520730Y-331582D01*
X520685Y-331594D01*
X520641Y-331605D01*
X520593Y-331623D01*
X520545Y-331645D01*
X520541Y-331649D01*
X520526Y-331657D01*
X520504Y-331675D01*
X520474Y-331694D01*
X520445Y-331719D01*
X520415Y-331753D01*
X520382Y-331786D01*
X520356Y-331827D01*
X520060Y-331786D01*
X520308Y-330469D01*
X521581D01*
Y-330768D01*
D02*
G37*
G36*
X518602Y-330439D02*
X518676Y-330443D01*
X518750Y-330450D01*
X518824Y-330461D01*
X518887Y-330472D01*
X518891D01*
X518898Y-330476D01*
X518909D01*
X518924Y-330484D01*
X518965Y-330495D01*
X519017Y-330513D01*
X519076Y-330539D01*
X519139Y-330572D01*
X519202Y-330609D01*
X519261Y-330658D01*
X519264Y-330661D01*
X519268Y-330665D01*
X519279Y-330676D01*
X519294Y-330687D01*
X519331Y-330724D01*
X519375Y-330776D01*
X519423Y-330839D01*
X519475Y-330913D01*
X519523Y-330998D01*
X519564Y-331094D01*
Y-331098D01*
X519568Y-331105D01*
X519575Y-331120D01*
X519579Y-331142D01*
X519590Y-331168D01*
X519597Y-331198D01*
X519605Y-331231D01*
X519616Y-331272D01*
X519627Y-331312D01*
X519634Y-331361D01*
X519653Y-331464D01*
X519664Y-331579D01*
X519668Y-331705D01*
Y-331708D01*
Y-331716D01*
Y-331734D01*
Y-331753D01*
X519664Y-331779D01*
Y-331808D01*
X519660Y-331878D01*
X519649Y-331960D01*
X519638Y-332045D01*
X519620Y-332134D01*
X519597Y-332223D01*
Y-332226D01*
X519594Y-332234D01*
X519590Y-332245D01*
X519586Y-332260D01*
X519571Y-332300D01*
X519549Y-332352D01*
X519527Y-332411D01*
X519497Y-332470D01*
X519460Y-332533D01*
X519423Y-332593D01*
X519420Y-332600D01*
X519405Y-332618D01*
X519383Y-332644D01*
X519353Y-332678D01*
X519320Y-332715D01*
X519279Y-332752D01*
X519239Y-332792D01*
X519190Y-332826D01*
X519183Y-332829D01*
X519168Y-332840D01*
X519142Y-332855D01*
X519105Y-332874D01*
X519061Y-332896D01*
X519009Y-332914D01*
X518950Y-332937D01*
X518883Y-332955D01*
X518876D01*
X518865Y-332959D01*
X518854Y-332963D01*
X518817Y-332966D01*
X518765Y-332974D01*
X518706Y-332981D01*
X518635Y-332989D01*
X518558Y-332992D01*
X518473Y-332996D01*
X517551D01*
Y-330435D01*
X518536D01*
X518602Y-330439D01*
D02*
G37*
G36*
X520873Y-346575D02*
X520899D01*
X520929Y-346579D01*
X520999Y-346594D01*
X521077Y-346612D01*
X521158Y-346642D01*
X521240Y-346686D01*
X521281Y-346712D01*
X521318Y-346742D01*
X521321Y-346746D01*
X521325Y-346749D01*
X521336Y-346760D01*
X521347Y-346772D01*
X521366Y-346790D01*
X521381Y-346812D01*
X521421Y-346864D01*
X521462Y-346931D01*
X521499Y-347012D01*
X521532Y-347105D01*
X521554Y-347208D01*
X521240Y-347234D01*
Y-347230D01*
X521236Y-347227D01*
X521232Y-347204D01*
X521221Y-347171D01*
X521207Y-347130D01*
X521192Y-347086D01*
X521170Y-347042D01*
X521144Y-347001D01*
X521118Y-346968D01*
X521110Y-346960D01*
X521096Y-346945D01*
X521070Y-346923D01*
X521033Y-346897D01*
X520985Y-346875D01*
X520933Y-346853D01*
X520870Y-346838D01*
X520803Y-346831D01*
X520777D01*
X520748Y-346834D01*
X520715Y-346842D01*
X520670Y-346853D01*
X520626Y-346868D01*
X520581Y-346886D01*
X520537Y-346916D01*
X520529Y-346919D01*
X520511Y-346934D01*
X520485Y-346960D01*
X520452Y-346997D01*
X520415Y-347042D01*
X520374Y-347093D01*
X520337Y-347160D01*
X520300Y-347234D01*
Y-347238D01*
X520296Y-347245D01*
X520293Y-347256D01*
X520285Y-347271D01*
X520282Y-347293D01*
X520274Y-347319D01*
X520267Y-347349D01*
X520259Y-347386D01*
X520248Y-347426D01*
X520241Y-347471D01*
X520233Y-347519D01*
X520230Y-347571D01*
X520222Y-347630D01*
X520219Y-347689D01*
X520215Y-347756D01*
Y-347822D01*
X520219Y-347819D01*
X520233Y-347796D01*
X520259Y-347767D01*
X520293Y-347730D01*
X520330Y-347685D01*
X520378Y-347645D01*
X520430Y-347604D01*
X520489Y-347567D01*
X520493D01*
X520496Y-347563D01*
X520518Y-347552D01*
X520552Y-347541D01*
X520596Y-347523D01*
X520648Y-347508D01*
X520707Y-347497D01*
X520770Y-347486D01*
X520836Y-347482D01*
X520866D01*
X520888Y-347486D01*
X520918Y-347489D01*
X520948Y-347493D01*
X520985Y-347500D01*
X521022Y-347512D01*
X521107Y-347537D01*
X521151Y-347556D01*
X521195Y-347582D01*
X521240Y-347608D01*
X521288Y-347637D01*
X521332Y-347674D01*
X521373Y-347715D01*
X521377Y-347719D01*
X521384Y-347726D01*
X521395Y-347737D01*
X521406Y-347756D01*
X521425Y-347782D01*
X521443Y-347808D01*
X521462Y-347841D01*
X521484Y-347878D01*
X521506Y-347919D01*
X521525Y-347963D01*
X521543Y-348015D01*
X521562Y-348066D01*
X521573Y-348122D01*
X521584Y-348185D01*
X521591Y-348248D01*
X521595Y-348314D01*
Y-348318D01*
Y-348325D01*
Y-348337D01*
Y-348355D01*
X521591Y-348377D01*
Y-348399D01*
X521580Y-348459D01*
X521569Y-348529D01*
X521551Y-348603D01*
X521525Y-348684D01*
X521488Y-348762D01*
Y-348766D01*
X521484Y-348769D01*
X521477Y-348781D01*
X521469Y-348795D01*
X521447Y-348832D01*
X521414Y-348881D01*
X521373Y-348932D01*
X521325Y-348984D01*
X521266Y-349036D01*
X521203Y-349080D01*
X521199D01*
X521195Y-349084D01*
X521184Y-349091D01*
X521170Y-349095D01*
X521133Y-349114D01*
X521084Y-349132D01*
X521022Y-349154D01*
X520951Y-349169D01*
X520873Y-349184D01*
X520788Y-349188D01*
X520770D01*
X520751Y-349184D01*
X520722D01*
X520689Y-349180D01*
X520652Y-349173D01*
X520607Y-349162D01*
X520563Y-349151D01*
X520511Y-349136D01*
X520459Y-349117D01*
X520407Y-349095D01*
X520352Y-349065D01*
X520300Y-349032D01*
X520248Y-348995D01*
X520196Y-348951D01*
X520148Y-348899D01*
X520145Y-348895D01*
X520137Y-348884D01*
X520126Y-348869D01*
X520111Y-348844D01*
X520089Y-348810D01*
X520071Y-348773D01*
X520048Y-348725D01*
X520026Y-348673D01*
X520000Y-348610D01*
X519978Y-348540D01*
X519960Y-348462D01*
X519941Y-348377D01*
X519923Y-348281D01*
X519911Y-348178D01*
X519904Y-348066D01*
X519901Y-347948D01*
Y-347944D01*
Y-347941D01*
Y-347930D01*
Y-347915D01*
X519904Y-347878D01*
Y-347826D01*
X519908Y-347767D01*
X519915Y-347696D01*
X519923Y-347619D01*
X519934Y-347534D01*
X519948Y-347449D01*
X519967Y-347356D01*
X519989Y-347267D01*
X520015Y-347179D01*
X520048Y-347093D01*
X520085Y-347012D01*
X520126Y-346934D01*
X520174Y-346868D01*
X520178Y-346864D01*
X520185Y-346857D01*
X520200Y-346842D01*
X520219Y-346820D01*
X520241Y-346797D01*
X520270Y-346775D01*
X520307Y-346746D01*
X520344Y-346720D01*
X520389Y-346694D01*
X520437Y-346664D01*
X520493Y-346642D01*
X520548Y-346616D01*
X520611Y-346598D01*
X520678Y-346583D01*
X520748Y-346575D01*
X520822Y-346572D01*
X520851D01*
X520873Y-346575D01*
D02*
G37*
G36*
X518513Y-346586D02*
X518587Y-346590D01*
X518661Y-346598D01*
X518735Y-346609D01*
X518798Y-346620D01*
X518802D01*
X518809Y-346623D01*
X518820D01*
X518835Y-346631D01*
X518876Y-346642D01*
X518927Y-346660D01*
X518987Y-346686D01*
X519049Y-346720D01*
X519112Y-346757D01*
X519172Y-346805D01*
X519175Y-346809D01*
X519179Y-346812D01*
X519190Y-346823D01*
X519205Y-346834D01*
X519242Y-346871D01*
X519286Y-346923D01*
X519334Y-346986D01*
X519386Y-347060D01*
X519434Y-347145D01*
X519475Y-347241D01*
Y-347245D01*
X519479Y-347252D01*
X519486Y-347267D01*
X519490Y-347289D01*
X519501Y-347315D01*
X519508Y-347345D01*
X519516Y-347378D01*
X519527Y-347419D01*
X519538Y-347460D01*
X519545Y-347508D01*
X519564Y-347611D01*
X519575Y-347726D01*
X519579Y-347852D01*
Y-347856D01*
Y-347863D01*
Y-347882D01*
Y-347900D01*
X519575Y-347926D01*
Y-347955D01*
X519571Y-348026D01*
X519560Y-348107D01*
X519549Y-348192D01*
X519530Y-348281D01*
X519508Y-348370D01*
Y-348374D01*
X519505Y-348381D01*
X519501Y-348392D01*
X519497Y-348407D01*
X519482Y-348448D01*
X519460Y-348499D01*
X519438Y-348559D01*
X519408Y-348618D01*
X519371Y-348681D01*
X519334Y-348740D01*
X519331Y-348747D01*
X519316Y-348766D01*
X519294Y-348792D01*
X519264Y-348825D01*
X519231Y-348862D01*
X519190Y-348899D01*
X519149Y-348940D01*
X519101Y-348973D01*
X519094Y-348977D01*
X519079Y-348988D01*
X519053Y-349003D01*
X519016Y-349021D01*
X518972Y-349043D01*
X518920Y-349062D01*
X518861Y-349084D01*
X518794Y-349102D01*
X518787D01*
X518776Y-349106D01*
X518764Y-349110D01*
X518727Y-349114D01*
X518676Y-349121D01*
X518617Y-349128D01*
X518546Y-349136D01*
X518469Y-349139D01*
X518383Y-349143D01*
X517462D01*
Y-346583D01*
X518446D01*
X518513Y-346586D01*
D02*
G37*
G36*
X638305Y-323719D02*
X638301Y-323786D01*
X638297Y-323860D01*
X638290Y-323934D01*
X638279Y-324008D01*
X638268Y-324071D01*
Y-324074D01*
X638264Y-324082D01*
Y-324093D01*
X638257Y-324108D01*
X638245Y-324148D01*
X638227Y-324200D01*
X638201Y-324259D01*
X638168Y-324322D01*
X638131Y-324385D01*
X638083Y-324444D01*
X638079Y-324448D01*
X638075Y-324452D01*
X638064Y-324463D01*
X638053Y-324478D01*
X638016Y-324515D01*
X637964Y-324559D01*
X637901Y-324607D01*
X637827Y-324659D01*
X637742Y-324707D01*
X637646Y-324748D01*
X637642D01*
X637635Y-324751D01*
X637620Y-324759D01*
X637598Y-324763D01*
X637572Y-324774D01*
X637542Y-324781D01*
X637509Y-324788D01*
X637468Y-324799D01*
X637428Y-324811D01*
X637380Y-324818D01*
X637276Y-324836D01*
X637161Y-324848D01*
X637036Y-324851D01*
X637032D01*
X637024D01*
X637006D01*
X636987D01*
X636962Y-324848D01*
X636932D01*
X636862Y-324844D01*
X636780Y-324833D01*
X636695Y-324822D01*
X636606Y-324803D01*
X636518Y-324781D01*
X636514D01*
X636507Y-324777D01*
X636495Y-324774D01*
X636481Y-324770D01*
X636440Y-324755D01*
X636388Y-324733D01*
X636329Y-324711D01*
X636270Y-324681D01*
X636207Y-324644D01*
X636148Y-324607D01*
X636140Y-324603D01*
X636122Y-324589D01*
X636096Y-324566D01*
X636062Y-324537D01*
X636025Y-324503D01*
X635989Y-324463D01*
X635948Y-324422D01*
X635915Y-324374D01*
X635911Y-324367D01*
X635900Y-324352D01*
X635885Y-324326D01*
X635866Y-324289D01*
X635844Y-324244D01*
X635826Y-324193D01*
X635804Y-324133D01*
X635785Y-324067D01*
Y-324060D01*
X635781Y-324048D01*
X635778Y-324037D01*
X635774Y-324000D01*
X635767Y-323949D01*
X635759Y-323889D01*
X635752Y-323819D01*
X635748Y-323741D01*
X635744Y-323656D01*
Y-322735D01*
X638305D01*
Y-323719D01*
D02*
G37*
G36*
X636521Y-325188D02*
X636544D01*
X636569Y-325192D01*
X636629Y-325199D01*
X636695Y-325214D01*
X636762Y-325236D01*
X636832Y-325269D01*
X636899Y-325310D01*
X636902D01*
X636906Y-325318D01*
X636925Y-325332D01*
X636954Y-325362D01*
X636991Y-325403D01*
X637028Y-325454D01*
X637069Y-325517D01*
X637102Y-325588D01*
X637128Y-325673D01*
Y-325669D01*
X637132Y-325665D01*
X637136Y-325654D01*
X637143Y-325639D01*
X637158Y-325606D01*
X637180Y-325562D01*
X637210Y-325514D01*
X637247Y-325465D01*
X637287Y-325421D01*
X637332Y-325380D01*
X637339Y-325377D01*
X637354Y-325366D01*
X637383Y-325351D01*
X637420Y-325336D01*
X637468Y-325318D01*
X637524Y-325303D01*
X637587Y-325292D01*
X637653Y-325288D01*
X637657D01*
X637665D01*
X637679D01*
X637702Y-325292D01*
X637724Y-325295D01*
X637753Y-325299D01*
X637816Y-325314D01*
X637890Y-325336D01*
X637968Y-325373D01*
X638009Y-325395D01*
X638049Y-325421D01*
X638086Y-325454D01*
X638123Y-325488D01*
X638127Y-325491D01*
X638131Y-325499D01*
X638142Y-325510D01*
X638153Y-325525D01*
X638168Y-325543D01*
X638183Y-325569D01*
X638201Y-325599D01*
X638220Y-325628D01*
X638238Y-325665D01*
X638257Y-325706D01*
X638271Y-325750D01*
X638286Y-325799D01*
X638308Y-325902D01*
X638312Y-325961D01*
X638316Y-326021D01*
Y-326054D01*
X638312Y-326076D01*
X638308Y-326106D01*
X638305Y-326139D01*
X638301Y-326176D01*
X638290Y-326213D01*
X638268Y-326302D01*
X638234Y-326391D01*
X638212Y-326435D01*
X638186Y-326479D01*
X638153Y-326520D01*
X638120Y-326561D01*
X638116Y-326564D01*
X638112Y-326568D01*
X638101Y-326579D01*
X638086Y-326594D01*
X638064Y-326609D01*
X638042Y-326627D01*
X637987Y-326664D01*
X637916Y-326701D01*
X637835Y-326735D01*
X637742Y-326761D01*
X637694Y-326764D01*
X637642Y-326768D01*
X637639D01*
X637635D01*
X637613D01*
X637579Y-326764D01*
X637539Y-326757D01*
X637487Y-326746D01*
X637435Y-326727D01*
X637383Y-326705D01*
X637332Y-326672D01*
X637324Y-326668D01*
X637309Y-326653D01*
X637287Y-326631D01*
X637258Y-326601D01*
X637224Y-326561D01*
X637191Y-326513D01*
X637158Y-326457D01*
X637128Y-326391D01*
Y-326394D01*
X637124Y-326402D01*
X637121Y-326413D01*
X637113Y-326428D01*
X637095Y-326472D01*
X637069Y-326524D01*
X637032Y-326579D01*
X636991Y-326638D01*
X636939Y-326694D01*
X636880Y-326746D01*
X636876D01*
X636873Y-326749D01*
X636851Y-326764D01*
X636814Y-326786D01*
X636765Y-326809D01*
X636706Y-326831D01*
X636636Y-326853D01*
X636558Y-326868D01*
X636473Y-326871D01*
X636470D01*
X636458D01*
X636440D01*
X636418Y-326868D01*
X636392Y-326864D01*
X636358Y-326860D01*
X636321Y-326853D01*
X636281Y-326842D01*
X636196Y-326816D01*
X636148Y-326798D01*
X636103Y-326772D01*
X636055Y-326746D01*
X636011Y-326716D01*
X635966Y-326679D01*
X635922Y-326638D01*
X635918Y-326635D01*
X635911Y-326627D01*
X635900Y-326616D01*
X635889Y-326598D01*
X635870Y-326572D01*
X635852Y-326546D01*
X635833Y-326513D01*
X635811Y-326476D01*
X635789Y-326435D01*
X635770Y-326387D01*
X635752Y-326335D01*
X635733Y-326283D01*
X635722Y-326224D01*
X635711Y-326161D01*
X635704Y-326098D01*
X635700Y-326028D01*
Y-325991D01*
X635704Y-325965D01*
X635707Y-325932D01*
X635711Y-325895D01*
X635718Y-325854D01*
X635730Y-325810D01*
X635755Y-325710D01*
X635774Y-325658D01*
X635792Y-325610D01*
X635818Y-325558D01*
X635848Y-325506D01*
X635881Y-325458D01*
X635922Y-325414D01*
X635926Y-325410D01*
X635933Y-325403D01*
X635944Y-325392D01*
X635963Y-325377D01*
X635985Y-325362D01*
X636011Y-325340D01*
X636040Y-325321D01*
X636077Y-325299D01*
X636114Y-325277D01*
X636159Y-325258D01*
X636251Y-325221D01*
X636307Y-325206D01*
X636362Y-325195D01*
X636421Y-325188D01*
X636481Y-325184D01*
X636484D01*
X636492D01*
X636507D01*
X636521Y-325188D01*
D02*
G37*
G36*
X656989Y-323819D02*
X656985Y-323886D01*
X656981Y-323960D01*
X656974Y-324034D01*
X656963Y-324108D01*
X656952Y-324171D01*
Y-324174D01*
X656948Y-324182D01*
Y-324193D01*
X656941Y-324208D01*
X656930Y-324249D01*
X656911Y-324300D01*
X656885Y-324359D01*
X656852Y-324422D01*
X656815Y-324485D01*
X656767Y-324545D01*
X656763Y-324548D01*
X656759Y-324552D01*
X656748Y-324563D01*
X656737Y-324578D01*
X656700Y-324615D01*
X656648Y-324659D01*
X656586Y-324707D01*
X656511Y-324759D01*
X656426Y-324807D01*
X656330Y-324848D01*
X656326D01*
X656319Y-324852D01*
X656304Y-324859D01*
X656282Y-324863D01*
X656256Y-324874D01*
X656227Y-324881D01*
X656193Y-324889D01*
X656153Y-324900D01*
X656112Y-324911D01*
X656064Y-324918D01*
X655960Y-324937D01*
X655845Y-324948D01*
X655720Y-324952D01*
X655716D01*
X655709D01*
X655690D01*
X655672D01*
X655646Y-324948D01*
X655616D01*
X655546Y-324944D01*
X655464Y-324933D01*
X655379Y-324922D01*
X655291Y-324903D01*
X655202Y-324881D01*
X655198D01*
X655191Y-324878D01*
X655180Y-324874D01*
X655165Y-324870D01*
X655124Y-324855D01*
X655072Y-324833D01*
X655013Y-324811D01*
X654954Y-324781D01*
X654891Y-324744D01*
X654832Y-324707D01*
X654824Y-324704D01*
X654806Y-324689D01*
X654780Y-324667D01*
X654747Y-324637D01*
X654710Y-324604D01*
X654673Y-324563D01*
X654632Y-324522D01*
X654599Y-324474D01*
X654595Y-324467D01*
X654584Y-324452D01*
X654569Y-324426D01*
X654551Y-324389D01*
X654528Y-324345D01*
X654510Y-324293D01*
X654488Y-324234D01*
X654469Y-324167D01*
Y-324160D01*
X654465Y-324149D01*
X654462Y-324138D01*
X654458Y-324101D01*
X654451Y-324049D01*
X654443Y-323990D01*
X654436Y-323919D01*
X654432Y-323842D01*
X654428Y-323756D01*
Y-322835D01*
X656989D01*
Y-323819D01*
D02*
G37*
G36*
X656955Y-326968D02*
X656708D01*
X656704Y-326964D01*
X656697Y-326957D01*
X656682Y-326942D01*
X656660Y-326927D01*
X656634Y-326905D01*
X656604Y-326876D01*
X656567Y-326846D01*
X656523Y-326813D01*
X656478Y-326779D01*
X656426Y-326739D01*
X656367Y-326698D01*
X656308Y-326657D01*
X656241Y-326613D01*
X656171Y-326568D01*
X656093Y-326524D01*
X656016Y-326480D01*
X656012Y-326476D01*
X655997Y-326469D01*
X655975Y-326458D01*
X655942Y-326439D01*
X655901Y-326420D01*
X655857Y-326398D01*
X655805Y-326372D01*
X655746Y-326346D01*
X655679Y-326317D01*
X655612Y-326284D01*
X655538Y-326254D01*
X655461Y-326224D01*
X655302Y-326165D01*
X655131Y-326110D01*
X655128D01*
X655117Y-326106D01*
X655098Y-326102D01*
X655076Y-326095D01*
X655046Y-326087D01*
X655009Y-326080D01*
X654969Y-326069D01*
X654924Y-326062D01*
X654872Y-326050D01*
X654817Y-326039D01*
X654699Y-326021D01*
X654569Y-326002D01*
X654428Y-325991D01*
Y-325669D01*
X654432D01*
X654443D01*
X654458D01*
X654480Y-325673D01*
X654510D01*
X654547Y-325677D01*
X654588Y-325680D01*
X654632Y-325684D01*
X654684Y-325692D01*
X654736Y-325699D01*
X654798Y-325710D01*
X654861Y-325721D01*
X654928Y-325732D01*
X655002Y-325747D01*
X655154Y-325784D01*
X655157D01*
X655172Y-325788D01*
X655194Y-325795D01*
X655228Y-325806D01*
X655265Y-325817D01*
X655309Y-325832D01*
X655361Y-325847D01*
X655416Y-325869D01*
X655479Y-325891D01*
X655542Y-325914D01*
X655683Y-325969D01*
X655831Y-326036D01*
X655979Y-326110D01*
X655982Y-326113D01*
X655997Y-326121D01*
X656016Y-326132D01*
X656045Y-326147D01*
X656079Y-326165D01*
X656119Y-326191D01*
X656164Y-326217D01*
X656212Y-326247D01*
X656319Y-326317D01*
X656430Y-326391D01*
X656545Y-326476D01*
X656652Y-326565D01*
Y-325310D01*
X656955D01*
Y-326968D01*
D02*
G37*
G36*
X649705Y-236241D02*
X647704D01*
X647707Y-236245D01*
X647722Y-236263D01*
X647744Y-236286D01*
X647770Y-236323D01*
X647804Y-236363D01*
X647841Y-236415D01*
X647881Y-236474D01*
X647922Y-236541D01*
Y-236545D01*
X647926Y-236548D01*
X647940Y-236571D01*
X647959Y-236608D01*
X647981Y-236652D01*
X648007Y-236704D01*
X648033Y-236759D01*
X648059Y-236815D01*
X648081Y-236870D01*
X647778D01*
Y-236867D01*
X647770Y-236859D01*
X647767Y-236844D01*
X647755Y-236826D01*
X647744Y-236804D01*
X647730Y-236778D01*
X647693Y-236715D01*
X647652Y-236641D01*
X647600Y-236567D01*
X647541Y-236489D01*
X647478Y-236411D01*
X647474Y-236408D01*
X647471Y-236404D01*
X647460Y-236393D01*
X647448Y-236378D01*
X647411Y-236345D01*
X647367Y-236300D01*
X647315Y-236256D01*
X647256Y-236208D01*
X647197Y-236167D01*
X647134Y-236130D01*
Y-235927D01*
X649705D01*
Y-236241D01*
D02*
G37*
G36*
X648914Y-237403D02*
X648936Y-237410D01*
X648965Y-237422D01*
X648999Y-237433D01*
X649039Y-237448D01*
X649084Y-237466D01*
X649132Y-237488D01*
X649235Y-237540D01*
X649339Y-237607D01*
X649391Y-237647D01*
X649443Y-237688D01*
X649487Y-237732D01*
X649532Y-237784D01*
X649535Y-237788D01*
X649543Y-237795D01*
X649550Y-237814D01*
X649565Y-237832D01*
X649583Y-237862D01*
X649602Y-237892D01*
X649620Y-237932D01*
X649639Y-237973D01*
X649661Y-238021D01*
X649680Y-238073D01*
X649698Y-238128D01*
X649717Y-238188D01*
X649731Y-238250D01*
X649739Y-238317D01*
X649746Y-238387D01*
X649750Y-238461D01*
Y-238502D01*
X649746Y-238532D01*
Y-238565D01*
X649742Y-238606D01*
X649735Y-238650D01*
X649728Y-238702D01*
X649709Y-238809D01*
X649680Y-238920D01*
X649639Y-239031D01*
X649613Y-239083D01*
X649583Y-239135D01*
X649580Y-239138D01*
X649576Y-239146D01*
X649565Y-239161D01*
X649550Y-239175D01*
X649535Y-239198D01*
X649513Y-239224D01*
X649487Y-239253D01*
X649458Y-239283D01*
X649424Y-239312D01*
X649391Y-239346D01*
X649306Y-239412D01*
X649206Y-239475D01*
X649095Y-239531D01*
X649091D01*
X649080Y-239538D01*
X649062Y-239542D01*
X649039Y-239553D01*
X649010Y-239560D01*
X648973Y-239571D01*
X648932Y-239586D01*
X648888Y-239597D01*
X648840Y-239608D01*
X648784Y-239623D01*
X648669Y-239642D01*
X648540Y-239656D01*
X648407Y-239664D01*
X648403D01*
X648388D01*
X648366D01*
X648340Y-239660D01*
X648303D01*
X648266Y-239656D01*
X648218Y-239653D01*
X648170Y-239645D01*
X648063Y-239627D01*
X647944Y-239601D01*
X647826Y-239564D01*
X647711Y-239512D01*
X647707Y-239508D01*
X647696Y-239505D01*
X647682Y-239497D01*
X647663Y-239482D01*
X647637Y-239468D01*
X647608Y-239449D01*
X647541Y-239401D01*
X647467Y-239338D01*
X647393Y-239264D01*
X647319Y-239179D01*
X647256Y-239079D01*
X647252Y-239075D01*
X647249Y-239064D01*
X647241Y-239050D01*
X647230Y-239031D01*
X647219Y-239001D01*
X647208Y-238972D01*
X647193Y-238935D01*
X647178Y-238894D01*
X647163Y-238850D01*
X647149Y-238802D01*
X647126Y-238698D01*
X647108Y-238580D01*
X647101Y-238458D01*
Y-238421D01*
X647104Y-238395D01*
X647108Y-238361D01*
X647112Y-238321D01*
X647115Y-238280D01*
X647126Y-238232D01*
X647149Y-238132D01*
X647182Y-238021D01*
X647204Y-237965D01*
X647230Y-237914D01*
X647263Y-237862D01*
X647297Y-237810D01*
X647300Y-237806D01*
X647304Y-237799D01*
X647315Y-237784D01*
X647334Y-237766D01*
X647352Y-237747D01*
X647378Y-237721D01*
X647408Y-237695D01*
X647437Y-237666D01*
X647474Y-237636D01*
X647519Y-237607D01*
X647563Y-237573D01*
X647611Y-237544D01*
X647667Y-237518D01*
X647722Y-237488D01*
X647781Y-237466D01*
X647848Y-237444D01*
X647926Y-237777D01*
X647922D01*
X647915Y-237780D01*
X647900Y-237788D01*
X647881Y-237795D01*
X647859Y-237803D01*
X647829Y-237814D01*
X647770Y-237843D01*
X647704Y-237880D01*
X647637Y-237925D01*
X647574Y-237980D01*
X647519Y-238039D01*
X647511Y-238047D01*
X647497Y-238069D01*
X647478Y-238106D01*
X647452Y-238154D01*
X647430Y-238217D01*
X647408Y-238287D01*
X647393Y-238372D01*
X647389Y-238465D01*
Y-238495D01*
X647393Y-238513D01*
Y-238539D01*
X647397Y-238569D01*
X647408Y-238639D01*
X647423Y-238717D01*
X647448Y-238798D01*
X647485Y-238883D01*
X647534Y-238961D01*
Y-238965D01*
X647541Y-238968D01*
X647559Y-238994D01*
X647589Y-239027D01*
X647633Y-239068D01*
X647689Y-239116D01*
X647752Y-239161D01*
X647829Y-239201D01*
X647915Y-239238D01*
X647918D01*
X647926Y-239242D01*
X647937Y-239246D01*
X647955Y-239249D01*
X647977Y-239257D01*
X648003Y-239264D01*
X648066Y-239275D01*
X648140Y-239290D01*
X648222Y-239305D01*
X648311Y-239312D01*
X648407Y-239316D01*
X648410D01*
X648421D01*
X648440D01*
X648462D01*
X648488Y-239312D01*
X648521D01*
X648558Y-239309D01*
X648599Y-239305D01*
X648688Y-239294D01*
X648784Y-239275D01*
X648880Y-239253D01*
X648977Y-239224D01*
X648980D01*
X648988Y-239220D01*
X648999Y-239212D01*
X649017Y-239205D01*
X649062Y-239183D01*
X649113Y-239149D01*
X649173Y-239109D01*
X649235Y-239057D01*
X649291Y-238998D01*
X649343Y-238928D01*
Y-238924D01*
X649346Y-238916D01*
X649354Y-238905D01*
X649361Y-238891D01*
X649369Y-238872D01*
X649380Y-238850D01*
X649402Y-238798D01*
X649424Y-238731D01*
X649443Y-238657D01*
X649458Y-238576D01*
X649461Y-238491D01*
Y-238465D01*
X649458Y-238443D01*
Y-238417D01*
X649454Y-238391D01*
X649439Y-238324D01*
X649420Y-238247D01*
X649391Y-238169D01*
X649350Y-238088D01*
X649328Y-238047D01*
X649298Y-238010D01*
X649295Y-238006D01*
X649291Y-238002D01*
X649280Y-237991D01*
X649269Y-237977D01*
X649250Y-237962D01*
X649228Y-237943D01*
X649206Y-237921D01*
X649176Y-237903D01*
X649143Y-237880D01*
X649106Y-237855D01*
X649069Y-237832D01*
X649025Y-237810D01*
X648977Y-237792D01*
X648925Y-237773D01*
X648869Y-237755D01*
X648810Y-237740D01*
X648895Y-237399D01*
X648899D01*
X648914Y-237403D01*
D02*
G37*
G36*
X560577Y-130052D02*
X560573D01*
X560558D01*
X560536D01*
X560507Y-130049D01*
X560473Y-130045D01*
X560436Y-130037D01*
X560399Y-130030D01*
X560359Y-130015D01*
X560355D01*
X560351Y-130011D01*
X560329Y-130004D01*
X560296Y-129989D01*
X560251Y-129967D01*
X560199Y-129937D01*
X560140Y-129901D01*
X560081Y-129860D01*
X560018Y-129808D01*
X560014D01*
X560011Y-129800D01*
X559989Y-129782D01*
X559955Y-129749D01*
X559907Y-129701D01*
X559852Y-129645D01*
X559785Y-129575D01*
X559711Y-129490D01*
X559633Y-129397D01*
X559630Y-129394D01*
X559619Y-129379D01*
X559600Y-129357D01*
X559578Y-129331D01*
X559548Y-129297D01*
X559515Y-129257D01*
X559478Y-129216D01*
X559437Y-129168D01*
X559348Y-129075D01*
X559260Y-128983D01*
X559215Y-128938D01*
X559171Y-128898D01*
X559130Y-128861D01*
X559090Y-128831D01*
X559086D01*
X559082Y-128824D01*
X559071Y-128816D01*
X559056Y-128809D01*
X559016Y-128783D01*
X558967Y-128753D01*
X558908Y-128727D01*
X558845Y-128702D01*
X558775Y-128687D01*
X558708Y-128679D01*
X558705D01*
X558701D01*
X558679Y-128683D01*
X558642Y-128687D01*
X558601Y-128698D01*
X558549Y-128713D01*
X558497Y-128739D01*
X558446Y-128772D01*
X558394Y-128816D01*
X558387Y-128824D01*
X558372Y-128842D01*
X558353Y-128868D01*
X558327Y-128909D01*
X558305Y-128961D01*
X558283Y-129020D01*
X558268Y-129090D01*
X558264Y-129168D01*
Y-129190D01*
X558268Y-129205D01*
X558272Y-129249D01*
X558283Y-129301D01*
X558298Y-129357D01*
X558324Y-129420D01*
X558357Y-129479D01*
X558401Y-129534D01*
X558409Y-129542D01*
X558427Y-129556D01*
X558457Y-129578D01*
X558501Y-129601D01*
X558553Y-129627D01*
X558620Y-129649D01*
X558694Y-129664D01*
X558779Y-129671D01*
X558745Y-129993D01*
X558742D01*
X558731Y-129989D01*
X558712D01*
X558686Y-129985D01*
X558657Y-129978D01*
X558623Y-129971D01*
X558583Y-129960D01*
X558542Y-129949D01*
X558453Y-129919D01*
X558364Y-129875D01*
X558320Y-129849D01*
X558276Y-129815D01*
X558235Y-129782D01*
X558198Y-129745D01*
X558194Y-129741D01*
X558190Y-129734D01*
X558179Y-129723D01*
X558168Y-129704D01*
X558153Y-129682D01*
X558139Y-129656D01*
X558120Y-129627D01*
X558102Y-129590D01*
X558083Y-129549D01*
X558065Y-129505D01*
X558050Y-129456D01*
X558035Y-129405D01*
X558024Y-129349D01*
X558013Y-129290D01*
X558009Y-129227D01*
X558005Y-129160D01*
Y-129123D01*
X558009Y-129098D01*
X558013Y-129068D01*
X558016Y-129031D01*
X558024Y-128990D01*
X558031Y-128949D01*
X558057Y-128853D01*
X558094Y-128757D01*
X558116Y-128709D01*
X558142Y-128661D01*
X558176Y-128617D01*
X558213Y-128576D01*
X558216Y-128572D01*
X558220Y-128565D01*
X558235Y-128557D01*
X558250Y-128543D01*
X558268Y-128524D01*
X558294Y-128506D01*
X558320Y-128487D01*
X558353Y-128465D01*
X558424Y-128428D01*
X558512Y-128391D01*
X558557Y-128376D01*
X558608Y-128369D01*
X558660Y-128361D01*
X558716Y-128358D01*
X558723D01*
X558742D01*
X558771Y-128361D01*
X558812Y-128365D01*
X558856Y-128372D01*
X558908Y-128387D01*
X558964Y-128402D01*
X559019Y-128424D01*
X559027Y-128428D01*
X559045Y-128435D01*
X559075Y-128450D01*
X559115Y-128472D01*
X559160Y-128502D01*
X559215Y-128539D01*
X559271Y-128583D01*
X559334Y-128635D01*
X559341Y-128642D01*
X559363Y-128661D01*
X559382Y-128679D01*
X559400Y-128698D01*
X559422Y-128720D01*
X559452Y-128750D01*
X559482Y-128779D01*
X559515Y-128816D01*
X559552Y-128853D01*
X559593Y-128898D01*
X559633Y-128946D01*
X559682Y-128998D01*
X559730Y-129057D01*
X559781Y-129116D01*
X559785Y-129120D01*
X559793Y-129127D01*
X559804Y-129142D01*
X559818Y-129160D01*
X559841Y-129183D01*
X559863Y-129209D01*
X559911Y-129268D01*
X559966Y-129331D01*
X560022Y-129390D01*
X560070Y-129442D01*
X560088Y-129464D01*
X560107Y-129482D01*
X560111Y-129486D01*
X560122Y-129497D01*
X560137Y-129512D01*
X560159Y-129530D01*
X560185Y-129549D01*
X560211Y-129571D01*
X560274Y-129616D01*
Y-128354D01*
X560577D01*
Y-130052D01*
D02*
G37*
G36*
X559593Y-130448D02*
X559630D01*
X559674Y-130452D01*
X559719Y-130455D01*
X559818Y-130467D01*
X559922Y-130481D01*
X560022Y-130503D01*
X560070Y-130518D01*
X560114Y-130533D01*
X560118D01*
X560125Y-130537D01*
X560137Y-130544D01*
X560151Y-130552D01*
X560192Y-130574D01*
X560244Y-130607D01*
X560303Y-130651D01*
X560362Y-130703D01*
X560425Y-130770D01*
X560481Y-130851D01*
Y-130855D01*
X560488Y-130862D01*
X560492Y-130874D01*
X560503Y-130892D01*
X560514Y-130914D01*
X560525Y-130944D01*
X560536Y-130973D01*
X560551Y-131010D01*
X560566Y-131051D01*
X560577Y-131096D01*
X560588Y-131144D01*
X560599Y-131199D01*
X560606Y-131255D01*
X560614Y-131314D01*
X560621Y-131447D01*
Y-131480D01*
X560618Y-131506D01*
Y-131536D01*
X560614Y-131573D01*
X560610Y-131614D01*
X560606Y-131654D01*
X560592Y-131747D01*
X560569Y-131847D01*
X560540Y-131943D01*
X560499Y-132035D01*
Y-132039D01*
X560492Y-132046D01*
X560484Y-132057D01*
X560477Y-132072D01*
X560447Y-132113D01*
X560407Y-132161D01*
X560355Y-132217D01*
X560296Y-132269D01*
X560222Y-132320D01*
X560140Y-132361D01*
X560137D01*
X560129Y-132365D01*
X560114Y-132368D01*
X560096Y-132376D01*
X560074Y-132383D01*
X560044Y-132391D01*
X560011Y-132402D01*
X559970Y-132409D01*
X559926Y-132416D01*
X559878Y-132428D01*
X559826Y-132435D01*
X559770Y-132442D01*
X559707Y-132450D01*
X559641Y-132453D01*
X559571Y-132457D01*
X559496D01*
X558016D01*
Y-132117D01*
X559496D01*
X559500D01*
X559511D01*
X559530D01*
X559552D01*
X559578Y-132113D01*
X559611D01*
X559682Y-132109D01*
X559763Y-132102D01*
X559844Y-132091D01*
X559922Y-132076D01*
X559955Y-132069D01*
X559989Y-132057D01*
X559996Y-132054D01*
X560014Y-132046D01*
X560040Y-132028D01*
X560077Y-132006D01*
X560114Y-131980D01*
X560155Y-131943D01*
X560196Y-131898D01*
X560229Y-131847D01*
X560233Y-131839D01*
X560244Y-131821D01*
X560255Y-131787D01*
X560270Y-131743D01*
X560288Y-131691D01*
X560299Y-131625D01*
X560311Y-131554D01*
X560314Y-131477D01*
Y-131440D01*
X560311Y-131418D01*
Y-131384D01*
X560307Y-131351D01*
X560292Y-131270D01*
X560274Y-131181D01*
X560244Y-131096D01*
X560203Y-131014D01*
X560177Y-130977D01*
X560148Y-130944D01*
X560144Y-130940D01*
X560140Y-130936D01*
X560129Y-130929D01*
X560114Y-130918D01*
X560092Y-130907D01*
X560070Y-130892D01*
X560037Y-130877D01*
X560003Y-130862D01*
X559963Y-130848D01*
X559915Y-130837D01*
X559859Y-130822D01*
X559800Y-130811D01*
X559733Y-130799D01*
X559663Y-130792D01*
X559582Y-130785D01*
X559496D01*
X558016D01*
Y-130444D01*
X559496D01*
X559500D01*
X559515D01*
X559534D01*
X559559D01*
X559593Y-130448D01*
D02*
G37*
G36*
X575765Y-116236D02*
X574740D01*
X574603Y-116928D01*
X574607Y-116924D01*
X574614Y-116921D01*
X574625Y-116913D01*
X574644Y-116902D01*
X574666Y-116891D01*
X574692Y-116876D01*
X574751Y-116847D01*
X574825Y-116817D01*
X574907Y-116791D01*
X574996Y-116773D01*
X575040Y-116765D01*
X575121D01*
X575143Y-116769D01*
X575173Y-116773D01*
X575206Y-116776D01*
X575243Y-116784D01*
X575284Y-116795D01*
X575373Y-116821D01*
X575421Y-116839D01*
X575469Y-116865D01*
X575517Y-116891D01*
X575565Y-116921D01*
X575610Y-116958D01*
X575654Y-116998D01*
X575658Y-117002D01*
X575665Y-117009D01*
X575676Y-117020D01*
X575691Y-117039D01*
X575710Y-117065D01*
X575728Y-117091D01*
X575750Y-117124D01*
X575772Y-117161D01*
X575791Y-117202D01*
X575813Y-117246D01*
X575832Y-117298D01*
X575850Y-117350D01*
X575865Y-117405D01*
X575876Y-117468D01*
X575883Y-117531D01*
X575887Y-117598D01*
Y-117601D01*
Y-117613D01*
Y-117631D01*
X575883Y-117657D01*
X575880Y-117686D01*
X575876Y-117720D01*
X575869Y-117761D01*
X575861Y-117801D01*
X575839Y-117897D01*
X575802Y-117997D01*
X575780Y-118049D01*
X575750Y-118097D01*
X575721Y-118149D01*
X575684Y-118197D01*
X575680Y-118201D01*
X575673Y-118212D01*
X575658Y-118227D01*
X575639Y-118245D01*
X575613Y-118267D01*
X575584Y-118297D01*
X575547Y-118323D01*
X575506Y-118352D01*
X575462Y-118382D01*
X575410Y-118408D01*
X575354Y-118434D01*
X575295Y-118460D01*
X575232Y-118478D01*
X575162Y-118493D01*
X575088Y-118504D01*
X575010Y-118508D01*
X574977D01*
X574951Y-118504D01*
X574922Y-118500D01*
X574888Y-118497D01*
X574848Y-118493D01*
X574807Y-118482D01*
X574714Y-118460D01*
X574622Y-118427D01*
X574574Y-118404D01*
X574526Y-118378D01*
X574481Y-118349D01*
X574437Y-118315D01*
X574433Y-118312D01*
X574426Y-118308D01*
X574418Y-118293D01*
X574403Y-118279D01*
X574385Y-118260D01*
X574367Y-118238D01*
X574344Y-118208D01*
X574326Y-118175D01*
X574304Y-118142D01*
X574281Y-118101D01*
X574241Y-118012D01*
X574207Y-117909D01*
X574196Y-117853D01*
X574189Y-117794D01*
X574518Y-117768D01*
Y-117772D01*
Y-117779D01*
X574522Y-117790D01*
X574526Y-117809D01*
X574537Y-117849D01*
X574551Y-117905D01*
X574574Y-117960D01*
X574603Y-118023D01*
X574640Y-118079D01*
X574685Y-118131D01*
X574692Y-118134D01*
X574707Y-118149D01*
X574736Y-118167D01*
X574777Y-118190D01*
X574822Y-118212D01*
X574877Y-118230D01*
X574940Y-118245D01*
X575010Y-118249D01*
X575033D01*
X575047Y-118245D01*
X575092Y-118242D01*
X575143Y-118227D01*
X575206Y-118208D01*
X575269Y-118179D01*
X575336Y-118134D01*
X575365Y-118108D01*
X575395Y-118079D01*
X575399Y-118075D01*
X575402Y-118071D01*
X575410Y-118060D01*
X575421Y-118049D01*
X575447Y-118008D01*
X575477Y-117957D01*
X575502Y-117894D01*
X575528Y-117816D01*
X575547Y-117724D01*
X575554Y-117675D01*
Y-117624D01*
Y-117620D01*
Y-117613D01*
Y-117598D01*
X575551Y-117579D01*
Y-117557D01*
X575547Y-117531D01*
X575536Y-117472D01*
X575517Y-117402D01*
X575491Y-117331D01*
X575454Y-117265D01*
X575402Y-117202D01*
Y-117198D01*
X575395Y-117194D01*
X575377Y-117176D01*
X575343Y-117150D01*
X575299Y-117120D01*
X575240Y-117095D01*
X575173Y-117069D01*
X575095Y-117050D01*
X575051Y-117043D01*
X574981D01*
X574951Y-117046D01*
X574914Y-117050D01*
X574870Y-117061D01*
X574825Y-117072D01*
X574777Y-117091D01*
X574729Y-117113D01*
X574725Y-117117D01*
X574711Y-117124D01*
X574688Y-117143D01*
X574659Y-117161D01*
X574629Y-117187D01*
X574600Y-117220D01*
X574566Y-117254D01*
X574540Y-117294D01*
X574244Y-117254D01*
X574492Y-115936D01*
X575765D01*
Y-116236D01*
D02*
G37*
G36*
X572957Y-115907D02*
X572990D01*
X573068Y-115910D01*
X573149Y-115922D01*
X573238Y-115933D01*
X573319Y-115951D01*
X573360Y-115962D01*
X573393Y-115973D01*
X573397D01*
X573401Y-115977D01*
X573423Y-115988D01*
X573456Y-116003D01*
X573497Y-116029D01*
X573541Y-116062D01*
X573590Y-116107D01*
X573634Y-116158D01*
X573678Y-116218D01*
Y-116221D01*
X573682Y-116225D01*
X573697Y-116247D01*
X573712Y-116284D01*
X573734Y-116332D01*
X573752Y-116388D01*
X573771Y-116454D01*
X573782Y-116525D01*
X573786Y-116602D01*
Y-116606D01*
Y-116613D01*
Y-116628D01*
X573782Y-116647D01*
Y-116673D01*
X573778Y-116699D01*
X573763Y-116762D01*
X573741Y-116835D01*
X573712Y-116913D01*
X573667Y-116991D01*
X573638Y-117028D01*
X573608Y-117065D01*
X573604Y-117069D01*
X573601Y-117072D01*
X573590Y-117083D01*
X573575Y-117095D01*
X573556Y-117109D01*
X573534Y-117124D01*
X573504Y-117143D01*
X573475Y-117165D01*
X573438Y-117183D01*
X573397Y-117202D01*
X573353Y-117224D01*
X573305Y-117243D01*
X573249Y-117257D01*
X573194Y-117276D01*
X573131Y-117287D01*
X573064Y-117298D01*
X573071Y-117302D01*
X573086Y-117309D01*
X573108Y-117324D01*
X573138Y-117339D01*
X573205Y-117379D01*
X573238Y-117405D01*
X573268Y-117428D01*
X573275Y-117435D01*
X573293Y-117453D01*
X573323Y-117483D01*
X573360Y-117520D01*
X573401Y-117572D01*
X573449Y-117627D01*
X573497Y-117694D01*
X573549Y-117768D01*
X573989Y-118464D01*
X573567D01*
X573231Y-117931D01*
Y-117927D01*
X573223Y-117920D01*
X573216Y-117909D01*
X573205Y-117894D01*
X573179Y-117853D01*
X573145Y-117801D01*
X573105Y-117746D01*
X573064Y-117686D01*
X573023Y-117631D01*
X572986Y-117579D01*
X572983Y-117576D01*
X572972Y-117561D01*
X572953Y-117538D01*
X572927Y-117513D01*
X572872Y-117457D01*
X572842Y-117431D01*
X572813Y-117409D01*
X572809Y-117405D01*
X572801Y-117402D01*
X572787Y-117394D01*
X572764Y-117383D01*
X572742Y-117372D01*
X572716Y-117361D01*
X572657Y-117342D01*
X572653D01*
X572646Y-117339D01*
X572631D01*
X572613Y-117335D01*
X572587Y-117331D01*
X572557D01*
X572516Y-117328D01*
X572080D01*
Y-118464D01*
X571739D01*
Y-115903D01*
X572927D01*
X572957Y-115907D01*
D02*
G37*
G36*
X277481Y-366202D02*
X277477Y-366232D01*
Y-366265D01*
X277474Y-366343D01*
X277463Y-366424D01*
X277451Y-366513D01*
X277433Y-366594D01*
X277422Y-366635D01*
X277411Y-366668D01*
Y-366672D01*
X277407Y-366676D01*
X277396Y-366698D01*
X277381Y-366731D01*
X277355Y-366772D01*
X277322Y-366816D01*
X277277Y-366864D01*
X277226Y-366909D01*
X277167Y-366953D01*
X277163D01*
X277159Y-366957D01*
X277137Y-366972D01*
X277100Y-366987D01*
X277052Y-367009D01*
X276996Y-367027D01*
X276930Y-367046D01*
X276859Y-367057D01*
X276782Y-367061D01*
X276778D01*
X276771D01*
X276756D01*
X276737Y-367057D01*
X276711D01*
X276686Y-367053D01*
X276623Y-367038D01*
X276549Y-367016D01*
X276471Y-366987D01*
X276393Y-366942D01*
X276356Y-366913D01*
X276319Y-366883D01*
X276315Y-366879D01*
X276312Y-366876D01*
X276301Y-366864D01*
X276290Y-366850D01*
X276275Y-366831D01*
X276260Y-366809D01*
X276241Y-366779D01*
X276219Y-366750D01*
X276201Y-366713D01*
X276182Y-366672D01*
X276160Y-366628D01*
X276142Y-366580D01*
X276127Y-366524D01*
X276108Y-366469D01*
X276097Y-366406D01*
X276086Y-366339D01*
X276082Y-366347D01*
X276075Y-366361D01*
X276060Y-366384D01*
X276045Y-366413D01*
X276005Y-366480D01*
X275979Y-366513D01*
X275957Y-366543D01*
X275949Y-366550D01*
X275931Y-366568D01*
X275901Y-366598D01*
X275864Y-366635D01*
X275812Y-366676D01*
X275757Y-366724D01*
X275690Y-366772D01*
X275616Y-366824D01*
X274921Y-367264D01*
Y-366842D01*
X275453Y-366506D01*
X275457D01*
X275465Y-366498D01*
X275476Y-366491D01*
X275490Y-366480D01*
X275531Y-366454D01*
X275583Y-366421D01*
X275638Y-366380D01*
X275698Y-366339D01*
X275753Y-366298D01*
X275805Y-366261D01*
X275809Y-366258D01*
X275823Y-366247D01*
X275846Y-366228D01*
X275871Y-366202D01*
X275927Y-366147D01*
X275953Y-366117D01*
X275975Y-366088D01*
X275979Y-366084D01*
X275982Y-366076D01*
X275990Y-366062D01*
X276001Y-366039D01*
X276012Y-366017D01*
X276023Y-365991D01*
X276042Y-365932D01*
Y-365928D01*
X276045Y-365921D01*
Y-365906D01*
X276049Y-365888D01*
X276053Y-365862D01*
Y-365832D01*
X276057Y-365792D01*
Y-365355D01*
X274921D01*
Y-365015D01*
X277481D01*
Y-366202D01*
D02*
G37*
G36*
X274991Y-367423D02*
X275024Y-367427D01*
X275061Y-367434D01*
X275098Y-367442D01*
X275139Y-367457D01*
X275143D01*
X275146Y-367460D01*
X275168Y-367468D01*
X275202Y-367482D01*
X275246Y-367505D01*
X275298Y-367534D01*
X275357Y-367571D01*
X275416Y-367612D01*
X275479Y-367664D01*
X275483D01*
X275487Y-367671D01*
X275509Y-367690D01*
X275542Y-367723D01*
X275590Y-367771D01*
X275646Y-367827D01*
X275712Y-367897D01*
X275786Y-367982D01*
X275864Y-368074D01*
X275868Y-368078D01*
X275879Y-368093D01*
X275897Y-368115D01*
X275920Y-368141D01*
X275949Y-368174D01*
X275982Y-368215D01*
X276020Y-368256D01*
X276060Y-368304D01*
X276149Y-368396D01*
X276238Y-368489D01*
X276282Y-368533D01*
X276327Y-368574D01*
X276367Y-368611D01*
X276408Y-368640D01*
X276412D01*
X276415Y-368648D01*
X276427Y-368655D01*
X276441Y-368663D01*
X276482Y-368689D01*
X276530Y-368718D01*
X276589Y-368744D01*
X276652Y-368770D01*
X276723Y-368785D01*
X276789Y-368792D01*
X276793D01*
X276797D01*
X276819Y-368789D01*
X276856Y-368785D01*
X276896Y-368774D01*
X276948Y-368759D01*
X277000Y-368733D01*
X277052Y-368700D01*
X277104Y-368655D01*
X277111Y-368648D01*
X277126Y-368629D01*
X277144Y-368603D01*
X277170Y-368563D01*
X277192Y-368511D01*
X277215Y-368452D01*
X277229Y-368382D01*
X277233Y-368304D01*
Y-368282D01*
X277229Y-368267D01*
X277226Y-368222D01*
X277215Y-368171D01*
X277200Y-368115D01*
X277174Y-368052D01*
X277141Y-367993D01*
X277096Y-367937D01*
X277089Y-367930D01*
X277070Y-367915D01*
X277041Y-367893D01*
X276996Y-367871D01*
X276944Y-367845D01*
X276878Y-367823D01*
X276804Y-367808D01*
X276719Y-367801D01*
X276752Y-367479D01*
X276756D01*
X276767Y-367482D01*
X276785D01*
X276811Y-367486D01*
X276841Y-367494D01*
X276874Y-367501D01*
X276915Y-367512D01*
X276956Y-367523D01*
X277044Y-367553D01*
X277133Y-367597D01*
X277178Y-367623D01*
X277222Y-367656D01*
X277263Y-367690D01*
X277300Y-367727D01*
X277303Y-367730D01*
X277307Y-367738D01*
X277318Y-367749D01*
X277329Y-367767D01*
X277344Y-367790D01*
X277359Y-367815D01*
X277377Y-367845D01*
X277396Y-367882D01*
X277414Y-367923D01*
X277433Y-367967D01*
X277448Y-368015D01*
X277463Y-368067D01*
X277474Y-368123D01*
X277485Y-368182D01*
X277488Y-368245D01*
X277492Y-368311D01*
Y-368348D01*
X277488Y-368374D01*
X277485Y-368404D01*
X277481Y-368441D01*
X277474Y-368481D01*
X277466Y-368522D01*
X277440Y-368618D01*
X277403Y-368714D01*
X277381Y-368763D01*
X277355Y-368811D01*
X277322Y-368855D01*
X277285Y-368896D01*
X277281Y-368899D01*
X277277Y-368907D01*
X277263Y-368914D01*
X277248Y-368929D01*
X277229Y-368948D01*
X277203Y-368966D01*
X277178Y-368985D01*
X277144Y-369007D01*
X277074Y-369044D01*
X276985Y-369081D01*
X276941Y-369096D01*
X276889Y-369103D01*
X276837Y-369110D01*
X276782Y-369114D01*
X276774D01*
X276756D01*
X276726Y-369110D01*
X276686Y-369107D01*
X276641Y-369099D01*
X276589Y-369085D01*
X276534Y-369070D01*
X276478Y-369047D01*
X276471Y-369044D01*
X276452Y-369036D01*
X276423Y-369022D01*
X276382Y-368999D01*
X276338Y-368970D01*
X276282Y-368933D01*
X276227Y-368888D01*
X276164Y-368837D01*
X276156Y-368829D01*
X276134Y-368811D01*
X276116Y-368792D01*
X276097Y-368774D01*
X276075Y-368752D01*
X276045Y-368722D01*
X276016Y-368692D01*
X275982Y-368655D01*
X275945Y-368618D01*
X275905Y-368574D01*
X275864Y-368526D01*
X275816Y-368474D01*
X275768Y-368415D01*
X275716Y-368356D01*
X275712Y-368352D01*
X275705Y-368344D01*
X275694Y-368330D01*
X275679Y-368311D01*
X275657Y-368289D01*
X275635Y-368263D01*
X275587Y-368204D01*
X275531Y-368141D01*
X275476Y-368082D01*
X275428Y-368030D01*
X275409Y-368008D01*
X275391Y-367989D01*
X275387Y-367986D01*
X275376Y-367974D01*
X275361Y-367960D01*
X275339Y-367941D01*
X275313Y-367923D01*
X275287Y-367900D01*
X275224Y-367856D01*
Y-369118D01*
X274921D01*
Y-367420D01*
X274924D01*
X274939D01*
X274961D01*
X274991Y-367423D01*
D02*
G37*
G36*
X277481Y-370520D02*
Y-370775D01*
X275823D01*
Y-371123D01*
X275535D01*
Y-370775D01*
X274921D01*
Y-370461D01*
X275535D01*
Y-369347D01*
X275823D01*
X277481Y-370520D01*
D02*
G37*
G36*
X653188Y-250881D02*
X651456D01*
Y-250578D01*
X652848D01*
Y-249786D01*
X651645D01*
Y-249482D01*
X652848D01*
Y-248321D01*
X653188D01*
Y-250881D01*
D02*
G37*
G36*
X650276Y-250322D02*
X650280Y-250319D01*
X650298Y-250304D01*
X650320Y-250282D01*
X650357Y-250256D01*
X650398Y-250222D01*
X650450Y-250185D01*
X650509Y-250145D01*
X650576Y-250104D01*
X650580D01*
X650583Y-250100D01*
X650605Y-250085D01*
X650642Y-250067D01*
X650687Y-250045D01*
X650739Y-250019D01*
X650794Y-249993D01*
X650850Y-249967D01*
X650905Y-249945D01*
Y-250248D01*
X650901D01*
X650894Y-250256D01*
X650879Y-250259D01*
X650861Y-250271D01*
X650839Y-250282D01*
X650813Y-250296D01*
X650750Y-250333D01*
X650676Y-250374D01*
X650602Y-250426D01*
X650524Y-250485D01*
X650446Y-250548D01*
X650443Y-250552D01*
X650439Y-250555D01*
X650428Y-250567D01*
X650413Y-250578D01*
X650380Y-250615D01*
X650335Y-250659D01*
X650291Y-250711D01*
X650243Y-250770D01*
X650202Y-250829D01*
X650165Y-250892D01*
X649962D01*
Y-248321D01*
X650276D01*
Y-250322D01*
D02*
G37*
G36*
X272253Y-365689D02*
X272335Y-365704D01*
X272405Y-365726D01*
X272464Y-365748D01*
X272512Y-365770D01*
X272549Y-365793D01*
X272571Y-365807D01*
X272579Y-365811D01*
X272634Y-365863D01*
X272682Y-365918D01*
X272720Y-365978D01*
X272749Y-366037D01*
X272771Y-366089D01*
X272786Y-366129D01*
X272790Y-366144D01*
X272793Y-366155D01*
X272797Y-366163D01*
Y-366166D01*
X272831Y-366103D01*
X272864Y-366052D01*
X272901Y-366007D01*
X272934Y-365970D01*
X272964Y-365941D01*
X272990Y-365918D01*
X273004Y-365907D01*
X273012Y-365904D01*
X273063Y-365874D01*
X273115Y-365852D01*
X273167Y-365833D01*
X273215Y-365822D01*
X273256Y-365815D01*
X273286Y-365811D01*
X273308D01*
X273315D01*
X273378Y-365815D01*
X273441Y-365826D01*
X273497Y-365841D01*
X273545Y-365859D01*
X273585Y-365878D01*
X273619Y-365893D01*
X273637Y-365904D01*
X273644Y-365907D01*
X273700Y-365944D01*
X273748Y-365989D01*
X273789Y-366033D01*
X273826Y-366077D01*
X273852Y-366114D01*
X273874Y-366148D01*
X273885Y-366170D01*
X273889Y-366174D01*
Y-366177D01*
X273918Y-366244D01*
X273940Y-366311D01*
X273959Y-366377D01*
X273970Y-366436D01*
X273977Y-366484D01*
X273981Y-366525D01*
Y-366618D01*
X273974Y-366670D01*
X273955Y-366769D01*
X273926Y-366855D01*
X273896Y-366929D01*
X273878Y-366962D01*
X273863Y-366988D01*
X273848Y-367014D01*
X273833Y-367032D01*
X273822Y-367047D01*
X273815Y-367058D01*
X273811Y-367065D01*
X273807Y-367069D01*
X273737Y-367139D01*
X273659Y-367195D01*
X273578Y-367239D01*
X273497Y-367276D01*
X273426Y-367299D01*
X273396Y-367310D01*
X273371Y-367317D01*
X273348Y-367321D01*
X273334Y-367324D01*
X273323Y-367328D01*
X273319D01*
X273263Y-367014D01*
X273345Y-366999D01*
X273415Y-366977D01*
X273474Y-366951D01*
X273522Y-366925D01*
X273559Y-366899D01*
X273585Y-366877D01*
X273604Y-366862D01*
X273607Y-366858D01*
X273644Y-366810D01*
X273674Y-366758D01*
X273692Y-366710D01*
X273707Y-366662D01*
X273715Y-366618D01*
X273722Y-366584D01*
Y-366555D01*
X273718Y-366488D01*
X273704Y-366429D01*
X273685Y-366377D01*
X273667Y-366333D01*
X273644Y-366300D01*
X273626Y-366274D01*
X273611Y-366255D01*
X273607Y-366251D01*
X273563Y-366211D01*
X273515Y-366181D01*
X273467Y-366163D01*
X273422Y-366148D01*
X273382Y-366140D01*
X273352Y-366133D01*
X273330D01*
X273326D01*
X273323D01*
X273282D01*
X273245Y-366140D01*
X273182Y-366159D01*
X273127Y-366185D01*
X273078Y-366214D01*
X273045Y-366244D01*
X273019Y-366270D01*
X273004Y-366288D01*
X273001Y-366292D01*
Y-366296D01*
X272967Y-366359D01*
X272941Y-366418D01*
X272923Y-366481D01*
X272912Y-366536D01*
X272904Y-366584D01*
X272897Y-366625D01*
Y-366673D01*
X272901Y-366688D01*
Y-366706D01*
X272623Y-366743D01*
X272634Y-366695D01*
X272642Y-366651D01*
X272649Y-366614D01*
X272653Y-366581D01*
X272657Y-366555D01*
Y-366522D01*
X272649Y-366444D01*
X272634Y-366373D01*
X272612Y-366311D01*
X272586Y-366259D01*
X272560Y-366218D01*
X272538Y-366189D01*
X272523Y-366170D01*
X272516Y-366163D01*
X272460Y-366114D01*
X272401Y-366077D01*
X272342Y-366052D01*
X272283Y-366037D01*
X272235Y-366026D01*
X272194Y-366022D01*
X272179Y-366018D01*
X272168D01*
X272161D01*
X272157D01*
X272076Y-366026D01*
X272002Y-366044D01*
X271939Y-366066D01*
X271883Y-366096D01*
X271839Y-366126D01*
X271806Y-366148D01*
X271783Y-366166D01*
X271776Y-366174D01*
X271724Y-366233D01*
X271687Y-366296D01*
X271661Y-366359D01*
X271643Y-366418D01*
X271632Y-366470D01*
X271628Y-366510D01*
X271624Y-366525D01*
Y-366547D01*
X271628Y-366614D01*
X271643Y-366677D01*
X271661Y-366732D01*
X271683Y-366777D01*
X271702Y-366814D01*
X271720Y-366843D01*
X271735Y-366858D01*
X271739Y-366866D01*
X271791Y-366910D01*
X271850Y-366947D01*
X271913Y-366980D01*
X271979Y-367006D01*
X272035Y-367025D01*
X272061Y-367032D01*
X272083Y-367036D01*
X272101Y-367039D01*
X272116Y-367043D01*
X272124Y-367047D01*
X272127D01*
X272087Y-367361D01*
X272028Y-367354D01*
X271972Y-367343D01*
X271868Y-367310D01*
X271780Y-367269D01*
X271743Y-367247D01*
X271706Y-367225D01*
X271672Y-367202D01*
X271646Y-367180D01*
X271621Y-367162D01*
X271602Y-367143D01*
X271587Y-367132D01*
X271576Y-367121D01*
X271569Y-367113D01*
X271565Y-367110D01*
X271532Y-367065D01*
X271498Y-367021D01*
X271473Y-366977D01*
X271450Y-366929D01*
X271413Y-366836D01*
X271391Y-366747D01*
X271384Y-366706D01*
X271376Y-366670D01*
X271373Y-366636D01*
X271369Y-366607D01*
X271365Y-366584D01*
Y-366551D01*
X271369Y-366481D01*
X271376Y-366418D01*
X271387Y-366355D01*
X271402Y-366296D01*
X271421Y-366240D01*
X271439Y-366192D01*
X271462Y-366144D01*
X271484Y-366103D01*
X271502Y-366063D01*
X271524Y-366029D01*
X271543Y-366000D01*
X271561Y-365978D01*
X271576Y-365959D01*
X271587Y-365944D01*
X271595Y-365937D01*
X271598Y-365933D01*
X271643Y-365889D01*
X271691Y-365852D01*
X271739Y-365819D01*
X271787Y-365789D01*
X271831Y-365767D01*
X271880Y-365744D01*
X271968Y-365715D01*
X272009Y-365707D01*
X272046Y-365700D01*
X272079Y-365693D01*
X272109Y-365689D01*
X272131Y-365685D01*
X272150D01*
X272161D01*
X272164D01*
X272253Y-365689D01*
D02*
G37*
G36*
X272342Y-367661D02*
X272405Y-367669D01*
X272468Y-367680D01*
X272523Y-367694D01*
X272575Y-367713D01*
X272627Y-367731D01*
X272671Y-367754D01*
X272712Y-367772D01*
X272749Y-367794D01*
X272782Y-367816D01*
X272808Y-367835D01*
X272834Y-367853D01*
X272853Y-367868D01*
X272864Y-367879D01*
X272871Y-367887D01*
X272875Y-367891D01*
X272916Y-367935D01*
X272953Y-367979D01*
X272982Y-368027D01*
X273008Y-368075D01*
X273034Y-368124D01*
X273052Y-368172D01*
X273078Y-368261D01*
X273089Y-368301D01*
X273097Y-368338D01*
X273101Y-368372D01*
X273104Y-368401D01*
X273108Y-368423D01*
Y-368505D01*
X273101Y-368549D01*
X273082Y-368638D01*
X273056Y-368719D01*
X273026Y-368793D01*
X272997Y-368852D01*
X272982Y-368878D01*
X272971Y-368901D01*
X272960Y-368919D01*
X272953Y-368930D01*
X272949Y-368938D01*
X272945Y-368941D01*
X273637Y-368804D01*
Y-367779D01*
X273937D01*
Y-369052D01*
X272620Y-369300D01*
X272579Y-369004D01*
X272620Y-368978D01*
X272653Y-368945D01*
X272686Y-368915D01*
X272712Y-368886D01*
X272730Y-368856D01*
X272749Y-368834D01*
X272756Y-368819D01*
X272760Y-368815D01*
X272782Y-368767D01*
X272801Y-368719D01*
X272812Y-368675D01*
X272823Y-368631D01*
X272827Y-368594D01*
X272831Y-368564D01*
Y-368494D01*
X272823Y-368449D01*
X272805Y-368372D01*
X272779Y-368305D01*
X272753Y-368246D01*
X272723Y-368201D01*
X272697Y-368168D01*
X272679Y-368149D01*
X272675Y-368142D01*
X272671D01*
X272608Y-368090D01*
X272542Y-368053D01*
X272471Y-368027D01*
X272401Y-368009D01*
X272342Y-367998D01*
X272316Y-367994D01*
X272294D01*
X272275Y-367990D01*
X272261D01*
X272253D01*
X272250D01*
X272198D01*
X272150Y-367998D01*
X272057Y-368016D01*
X271979Y-368042D01*
X271917Y-368068D01*
X271865Y-368098D01*
X271824Y-368124D01*
X271813Y-368135D01*
X271802Y-368142D01*
X271798Y-368146D01*
X271795Y-368149D01*
X271765Y-368179D01*
X271739Y-368209D01*
X271694Y-368275D01*
X271665Y-368338D01*
X271646Y-368401D01*
X271632Y-368453D01*
X271628Y-368497D01*
X271624Y-368512D01*
Y-368534D01*
X271628Y-368605D01*
X271643Y-368668D01*
X271661Y-368723D01*
X271683Y-368767D01*
X271706Y-368808D01*
X271724Y-368838D01*
X271739Y-368852D01*
X271743Y-368860D01*
X271795Y-368904D01*
X271850Y-368941D01*
X271913Y-368971D01*
X271968Y-368993D01*
X272024Y-369008D01*
X272065Y-369019D01*
X272083Y-369023D01*
X272094Y-369026D01*
X272101D01*
X272105D01*
X272079Y-369356D01*
X272020Y-369348D01*
X271965Y-369337D01*
X271861Y-369304D01*
X271772Y-369263D01*
X271732Y-369241D01*
X271698Y-369219D01*
X271665Y-369200D01*
X271635Y-369178D01*
X271613Y-369160D01*
X271595Y-369141D01*
X271580Y-369126D01*
X271565Y-369119D01*
X271561Y-369111D01*
X271558Y-369108D01*
X271524Y-369063D01*
X271495Y-369019D01*
X271469Y-368971D01*
X271447Y-368923D01*
X271413Y-368830D01*
X271391Y-368738D01*
X271380Y-368697D01*
X271376Y-368656D01*
X271373Y-368623D01*
X271369Y-368594D01*
X271365Y-368568D01*
Y-368534D01*
X271369Y-368457D01*
X271380Y-368383D01*
X271395Y-368312D01*
X271413Y-368249D01*
X271439Y-368190D01*
X271465Y-368135D01*
X271491Y-368083D01*
X271521Y-368039D01*
X271550Y-367998D01*
X271576Y-367961D01*
X271606Y-367931D01*
X271628Y-367905D01*
X271646Y-367887D01*
X271661Y-367872D01*
X271672Y-367865D01*
X271676Y-367861D01*
X271724Y-367824D01*
X271776Y-367794D01*
X271824Y-367765D01*
X271876Y-367742D01*
X271976Y-367705D01*
X272072Y-367683D01*
X272113Y-367676D01*
X272153Y-367669D01*
X272187Y-367665D01*
X272216Y-367661D01*
X272242Y-367657D01*
X272261D01*
X272272D01*
X272275D01*
X272342Y-367661D01*
D02*
G37*
G36*
X272305Y-369985D02*
X272246Y-370000D01*
X272190Y-370018D01*
X272139Y-370037D01*
X272091Y-370055D01*
X272046Y-370077D01*
X272009Y-370099D01*
X271972Y-370125D01*
X271939Y-370147D01*
X271909Y-370166D01*
X271887Y-370188D01*
X271865Y-370207D01*
X271846Y-370221D01*
X271835Y-370236D01*
X271824Y-370247D01*
X271820Y-370251D01*
X271817Y-370255D01*
X271787Y-370292D01*
X271765Y-370333D01*
X271724Y-370414D01*
X271694Y-370492D01*
X271676Y-370569D01*
X271661Y-370636D01*
X271657Y-370662D01*
Y-370688D01*
X271654Y-370710D01*
Y-370736D01*
X271657Y-370821D01*
X271672Y-370902D01*
X271691Y-370976D01*
X271713Y-371043D01*
X271735Y-371095D01*
X271746Y-371117D01*
X271754Y-371135D01*
X271761Y-371150D01*
X271769Y-371161D01*
X271772Y-371169D01*
Y-371172D01*
X271824Y-371243D01*
X271880Y-371302D01*
X271942Y-371354D01*
X272002Y-371394D01*
X272054Y-371428D01*
X272098Y-371450D01*
X272116Y-371457D01*
X272127Y-371465D01*
X272135Y-371468D01*
X272139D01*
X272235Y-371498D01*
X272331Y-371520D01*
X272427Y-371539D01*
X272516Y-371550D01*
X272557Y-371553D01*
X272594Y-371557D01*
X272627D01*
X272653Y-371561D01*
X272675D01*
X272694D01*
X272705D01*
X272708D01*
X272805Y-371557D01*
X272893Y-371550D01*
X272975Y-371535D01*
X273049Y-371520D01*
X273112Y-371509D01*
X273138Y-371502D01*
X273160Y-371494D01*
X273178Y-371491D01*
X273189Y-371487D01*
X273197Y-371483D01*
X273200D01*
X273286Y-371446D01*
X273363Y-371406D01*
X273426Y-371361D01*
X273482Y-371313D01*
X273526Y-371272D01*
X273556Y-371239D01*
X273574Y-371213D01*
X273582Y-371209D01*
Y-371206D01*
X273630Y-371128D01*
X273667Y-371043D01*
X273692Y-370961D01*
X273707Y-370884D01*
X273718Y-370813D01*
X273722Y-370784D01*
Y-370758D01*
X273726Y-370740D01*
Y-370710D01*
X273722Y-370617D01*
X273707Y-370532D01*
X273685Y-370462D01*
X273663Y-370399D01*
X273637Y-370351D01*
X273619Y-370314D01*
X273604Y-370292D01*
X273596Y-370284D01*
X273541Y-370225D01*
X273478Y-370170D01*
X273411Y-370125D01*
X273345Y-370088D01*
X273286Y-370059D01*
X273256Y-370048D01*
X273234Y-370040D01*
X273215Y-370033D01*
X273200Y-370025D01*
X273193Y-370022D01*
X273189D01*
X273267Y-369689D01*
X273334Y-369711D01*
X273393Y-369733D01*
X273448Y-369763D01*
X273504Y-369789D01*
X273552Y-369818D01*
X273596Y-369851D01*
X273641Y-369881D01*
X273678Y-369911D01*
X273707Y-369940D01*
X273737Y-369966D01*
X273763Y-369992D01*
X273781Y-370011D01*
X273800Y-370029D01*
X273811Y-370044D01*
X273815Y-370051D01*
X273818Y-370055D01*
X273852Y-370107D01*
X273885Y-370159D01*
X273911Y-370210D01*
X273933Y-370266D01*
X273966Y-370377D01*
X273989Y-370477D01*
X274000Y-370525D01*
X274003Y-370566D01*
X274007Y-370606D01*
X274011Y-370640D01*
X274014Y-370666D01*
Y-370703D01*
X274007Y-370825D01*
X273989Y-370943D01*
X273966Y-371047D01*
X273952Y-371095D01*
X273937Y-371139D01*
X273922Y-371180D01*
X273907Y-371217D01*
X273896Y-371246D01*
X273885Y-371276D01*
X273874Y-371294D01*
X273866Y-371309D01*
X273863Y-371320D01*
X273859Y-371324D01*
X273796Y-371424D01*
X273722Y-371509D01*
X273648Y-371583D01*
X273574Y-371646D01*
X273507Y-371694D01*
X273478Y-371713D01*
X273452Y-371727D01*
X273434Y-371742D01*
X273419Y-371750D01*
X273408Y-371753D01*
X273404Y-371757D01*
X273289Y-371809D01*
X273171Y-371846D01*
X273052Y-371872D01*
X272945Y-371890D01*
X272897Y-371898D01*
X272849Y-371901D01*
X272812Y-371905D01*
X272775D01*
X272749Y-371909D01*
X272727D01*
X272712D01*
X272708D01*
X272575Y-371901D01*
X272446Y-371886D01*
X272331Y-371868D01*
X272275Y-371853D01*
X272227Y-371842D01*
X272183Y-371831D01*
X272142Y-371816D01*
X272105Y-371805D01*
X272076Y-371798D01*
X272054Y-371787D01*
X272035Y-371783D01*
X272024Y-371776D01*
X272020D01*
X271909Y-371720D01*
X271809Y-371657D01*
X271724Y-371590D01*
X271691Y-371557D01*
X271657Y-371528D01*
X271628Y-371498D01*
X271602Y-371468D01*
X271580Y-371443D01*
X271565Y-371420D01*
X271550Y-371406D01*
X271539Y-371391D01*
X271535Y-371383D01*
X271532Y-371380D01*
X271502Y-371328D01*
X271476Y-371276D01*
X271436Y-371165D01*
X271406Y-371054D01*
X271387Y-370947D01*
X271380Y-370895D01*
X271373Y-370850D01*
X271369Y-370810D01*
Y-370777D01*
X271365Y-370747D01*
Y-370706D01*
X271369Y-370632D01*
X271376Y-370562D01*
X271384Y-370495D01*
X271398Y-370432D01*
X271417Y-370373D01*
X271436Y-370318D01*
X271454Y-370266D01*
X271476Y-370218D01*
X271495Y-370177D01*
X271513Y-370136D01*
X271532Y-370107D01*
X271550Y-370077D01*
X271565Y-370059D01*
X271572Y-370040D01*
X271580Y-370033D01*
X271584Y-370029D01*
X271628Y-369977D01*
X271672Y-369933D01*
X271724Y-369892D01*
X271776Y-369851D01*
X271880Y-369785D01*
X271983Y-369733D01*
X272031Y-369711D01*
X272076Y-369692D01*
X272116Y-369678D01*
X272150Y-369667D01*
X272179Y-369655D01*
X272201Y-369648D01*
X272216Y-369644D01*
X272220D01*
X272305Y-369985D01*
D02*
G37*
G36*
X548510Y-151824D02*
X548547D01*
X548584Y-151828D01*
X548632Y-151832D01*
X548680Y-151839D01*
X548788Y-151858D01*
X548906Y-151883D01*
X549025Y-151920D01*
X549139Y-151972D01*
X549143Y-151976D01*
X549154Y-151980D01*
X549169Y-151987D01*
X549187Y-152002D01*
X549213Y-152017D01*
X549243Y-152035D01*
X549309Y-152083D01*
X549383Y-152146D01*
X549458Y-152220D01*
X549532Y-152305D01*
X549594Y-152405D01*
X549598Y-152409D01*
X549602Y-152420D01*
X549609Y-152435D01*
X549620Y-152453D01*
X549631Y-152483D01*
X549643Y-152513D01*
X549657Y-152550D01*
X549672Y-152590D01*
X549687Y-152635D01*
X549702Y-152683D01*
X549724Y-152786D01*
X549742Y-152905D01*
X549750Y-153027D01*
Y-153064D01*
X549746Y-153090D01*
X549742Y-153123D01*
X549739Y-153164D01*
X549735Y-153204D01*
X549724Y-153252D01*
X549702Y-153352D01*
X549668Y-153463D01*
X549646Y-153519D01*
X549620Y-153571D01*
X549587Y-153622D01*
X549554Y-153674D01*
X549550Y-153678D01*
X549546Y-153685D01*
X549535Y-153700D01*
X549517Y-153719D01*
X549498Y-153737D01*
X549472Y-153763D01*
X549443Y-153789D01*
X549413Y-153819D01*
X549376Y-153848D01*
X549332Y-153878D01*
X549287Y-153911D01*
X549239Y-153941D01*
X549184Y-153967D01*
X549128Y-153996D01*
X549069Y-154018D01*
X549002Y-154041D01*
X548925Y-153708D01*
X548928D01*
X548936Y-153704D01*
X548951Y-153697D01*
X548969Y-153689D01*
X548991Y-153682D01*
X549021Y-153671D01*
X549080Y-153641D01*
X549147Y-153604D01*
X549213Y-153560D01*
X549276Y-153504D01*
X549332Y-153445D01*
X549339Y-153437D01*
X549354Y-153415D01*
X549372Y-153378D01*
X549398Y-153330D01*
X549420Y-153267D01*
X549443Y-153197D01*
X549458Y-153112D01*
X549461Y-153019D01*
Y-152990D01*
X549458Y-152971D01*
Y-152945D01*
X549454Y-152916D01*
X549443Y-152846D01*
X549428Y-152768D01*
X549402Y-152686D01*
X549365Y-152601D01*
X549317Y-152524D01*
Y-152520D01*
X549309Y-152516D01*
X549291Y-152490D01*
X549261Y-152457D01*
X549217Y-152416D01*
X549161Y-152368D01*
X549099Y-152324D01*
X549021Y-152283D01*
X548936Y-152246D01*
X548932D01*
X548925Y-152242D01*
X548914Y-152239D01*
X548895Y-152235D01*
X548873Y-152228D01*
X548847Y-152220D01*
X548784Y-152209D01*
X548710Y-152194D01*
X548629Y-152180D01*
X548540Y-152172D01*
X548444Y-152168D01*
X548440D01*
X548429D01*
X548410D01*
X548388D01*
X548362Y-152172D01*
X548329D01*
X548292Y-152176D01*
X548251Y-152180D01*
X548163Y-152191D01*
X548066Y-152209D01*
X547970Y-152231D01*
X547874Y-152261D01*
X547870D01*
X547863Y-152265D01*
X547852Y-152272D01*
X547833Y-152279D01*
X547789Y-152302D01*
X547737Y-152335D01*
X547678Y-152376D01*
X547615Y-152427D01*
X547559Y-152487D01*
X547508Y-152557D01*
Y-152561D01*
X547504Y-152568D01*
X547497Y-152579D01*
X547489Y-152594D01*
X547482Y-152612D01*
X547471Y-152635D01*
X547448Y-152686D01*
X547426Y-152753D01*
X547408Y-152827D01*
X547393Y-152908D01*
X547389Y-152994D01*
Y-153019D01*
X547393Y-153042D01*
Y-153068D01*
X547397Y-153093D01*
X547411Y-153160D01*
X547430Y-153238D01*
X547460Y-153315D01*
X547500Y-153397D01*
X547522Y-153437D01*
X547552Y-153474D01*
X547556Y-153478D01*
X547559Y-153482D01*
X547571Y-153493D01*
X547582Y-153508D01*
X547600Y-153523D01*
X547622Y-153541D01*
X547645Y-153563D01*
X547674Y-153582D01*
X547707Y-153604D01*
X547744Y-153630D01*
X547781Y-153652D01*
X547826Y-153674D01*
X547874Y-153693D01*
X547926Y-153711D01*
X547981Y-153730D01*
X548040Y-153745D01*
X547955Y-154085D01*
X547952D01*
X547937Y-154081D01*
X547915Y-154074D01*
X547885Y-154063D01*
X547852Y-154052D01*
X547811Y-154037D01*
X547767Y-154018D01*
X547718Y-153996D01*
X547615Y-153944D01*
X547511Y-153878D01*
X547460Y-153837D01*
X547408Y-153796D01*
X547363Y-153752D01*
X547319Y-153700D01*
X547315Y-153697D01*
X547308Y-153689D01*
X547300Y-153671D01*
X547286Y-153652D01*
X547267Y-153622D01*
X547249Y-153593D01*
X547230Y-153552D01*
X547212Y-153512D01*
X547189Y-153463D01*
X547171Y-153412D01*
X547152Y-153356D01*
X547134Y-153297D01*
X547119Y-153234D01*
X547112Y-153167D01*
X547104Y-153097D01*
X547101Y-153023D01*
Y-152982D01*
X547104Y-152953D01*
Y-152919D01*
X547108Y-152879D01*
X547115Y-152834D01*
X547123Y-152783D01*
X547141Y-152675D01*
X547171Y-152564D01*
X547212Y-152453D01*
X547237Y-152401D01*
X547267Y-152350D01*
X547271Y-152346D01*
X547274Y-152339D01*
X547286Y-152324D01*
X547300Y-152309D01*
X547315Y-152287D01*
X547337Y-152261D01*
X547363Y-152231D01*
X547393Y-152202D01*
X547426Y-152172D01*
X547460Y-152139D01*
X547545Y-152072D01*
X547645Y-152009D01*
X547755Y-151954D01*
X547759D01*
X547770Y-151946D01*
X547789Y-151943D01*
X547811Y-151932D01*
X547841Y-151924D01*
X547878Y-151913D01*
X547918Y-151898D01*
X547963Y-151887D01*
X548011Y-151876D01*
X548066Y-151861D01*
X548181Y-151843D01*
X548311Y-151828D01*
X548444Y-151821D01*
X548447D01*
X548462D01*
X548484D01*
X548510Y-151824D01*
D02*
G37*
G36*
X547863Y-154692D02*
X547859D01*
X547852Y-154695D01*
X547837Y-154699D01*
X547818Y-154703D01*
X547796Y-154707D01*
X547770Y-154714D01*
X547715Y-154733D01*
X547648Y-154758D01*
X547585Y-154792D01*
X547526Y-154829D01*
X547474Y-154873D01*
X547471Y-154880D01*
X547456Y-154895D01*
X547437Y-154925D01*
X547419Y-154962D01*
X547397Y-155006D01*
X547378Y-155062D01*
X547363Y-155125D01*
X547360Y-155191D01*
Y-155213D01*
X547363Y-155228D01*
X547367Y-155269D01*
X547378Y-155321D01*
X547397Y-155380D01*
X547423Y-155443D01*
X547460Y-155506D01*
X547511Y-155565D01*
X547519Y-155572D01*
X547541Y-155591D01*
X547574Y-155613D01*
X547619Y-155643D01*
X547674Y-155672D01*
X547737Y-155694D01*
X547811Y-155713D01*
X547892Y-155720D01*
X547896D01*
X547903D01*
X547915D01*
X547929Y-155717D01*
X547970Y-155713D01*
X548018Y-155702D01*
X548077Y-155687D01*
X548137Y-155661D01*
X548196Y-155624D01*
X548251Y-155576D01*
X548259Y-155569D01*
X548274Y-155550D01*
X548296Y-155521D01*
X548322Y-155480D01*
X548348Y-155428D01*
X548370Y-155365D01*
X548385Y-155295D01*
X548392Y-155217D01*
Y-155184D01*
X548388Y-155158D01*
X548385Y-155125D01*
X548377Y-155088D01*
X548370Y-155043D01*
X548359Y-154995D01*
X548636Y-155032D01*
Y-155051D01*
X548632Y-155066D01*
Y-155114D01*
X548640Y-155154D01*
X548647Y-155202D01*
X548658Y-155258D01*
X548677Y-155321D01*
X548703Y-155380D01*
X548736Y-155443D01*
Y-155447D01*
X548740Y-155450D01*
X548755Y-155469D01*
X548780Y-155495D01*
X548814Y-155524D01*
X548862Y-155554D01*
X548917Y-155580D01*
X548980Y-155598D01*
X549017Y-155606D01*
X549058D01*
X549062D01*
X549065D01*
X549087D01*
X549117Y-155598D01*
X549158Y-155591D01*
X549202Y-155576D01*
X549250Y-155558D01*
X549298Y-155528D01*
X549343Y-155487D01*
X549346Y-155484D01*
X549361Y-155465D01*
X549380Y-155439D01*
X549402Y-155406D01*
X549420Y-155361D01*
X549439Y-155310D01*
X549454Y-155251D01*
X549458Y-155184D01*
Y-155154D01*
X549450Y-155121D01*
X549443Y-155077D01*
X549428Y-155028D01*
X549409Y-154980D01*
X549380Y-154929D01*
X549343Y-154880D01*
X549339Y-154877D01*
X549321Y-154862D01*
X549295Y-154840D01*
X549258Y-154814D01*
X549210Y-154788D01*
X549150Y-154762D01*
X549080Y-154740D01*
X548999Y-154725D01*
X549054Y-154411D01*
X549058D01*
X549069Y-154414D01*
X549084Y-154418D01*
X549106Y-154422D01*
X549132Y-154429D01*
X549161Y-154440D01*
X549232Y-154462D01*
X549313Y-154499D01*
X549395Y-154544D01*
X549472Y-154599D01*
X549543Y-154670D01*
X549546Y-154673D01*
X549550Y-154681D01*
X549557Y-154692D01*
X549569Y-154707D01*
X549583Y-154725D01*
X549598Y-154751D01*
X549613Y-154777D01*
X549631Y-154810D01*
X549661Y-154884D01*
X549691Y-154969D01*
X549709Y-155069D01*
X549717Y-155121D01*
Y-155213D01*
X549713Y-155254D01*
X549705Y-155302D01*
X549694Y-155361D01*
X549676Y-155428D01*
X549654Y-155495D01*
X549624Y-155561D01*
Y-155565D01*
X549620Y-155569D01*
X549609Y-155591D01*
X549587Y-155624D01*
X549561Y-155661D01*
X549524Y-155706D01*
X549483Y-155750D01*
X549435Y-155794D01*
X549380Y-155831D01*
X549372Y-155835D01*
X549354Y-155846D01*
X549321Y-155861D01*
X549280Y-155879D01*
X549232Y-155898D01*
X549176Y-155913D01*
X549113Y-155924D01*
X549051Y-155928D01*
X549043D01*
X549021D01*
X548991Y-155924D01*
X548951Y-155917D01*
X548903Y-155905D01*
X548851Y-155887D01*
X548799Y-155865D01*
X548747Y-155835D01*
X548740Y-155831D01*
X548725Y-155820D01*
X548699Y-155798D01*
X548669Y-155769D01*
X548636Y-155731D01*
X548599Y-155687D01*
X548566Y-155635D01*
X548532Y-155572D01*
Y-155576D01*
X548529Y-155584D01*
X548525Y-155595D01*
X548521Y-155609D01*
X548507Y-155650D01*
X548484Y-155702D01*
X548455Y-155761D01*
X548418Y-155820D01*
X548370Y-155876D01*
X548314Y-155928D01*
X548307Y-155931D01*
X548285Y-155946D01*
X548248Y-155968D01*
X548200Y-155991D01*
X548140Y-156013D01*
X548070Y-156035D01*
X547989Y-156050D01*
X547900Y-156053D01*
X547896D01*
X547885D01*
X547866D01*
X547844Y-156050D01*
X547815Y-156046D01*
X547781Y-156039D01*
X547744Y-156031D01*
X547704Y-156024D01*
X547615Y-155994D01*
X547567Y-155972D01*
X547522Y-155950D01*
X547474Y-155920D01*
X547426Y-155887D01*
X547378Y-155850D01*
X547334Y-155806D01*
X547330Y-155802D01*
X547323Y-155794D01*
X547311Y-155780D01*
X547297Y-155761D01*
X547278Y-155739D01*
X547260Y-155709D01*
X547237Y-155676D01*
X547219Y-155635D01*
X547197Y-155595D01*
X547175Y-155546D01*
X547156Y-155498D01*
X547138Y-155443D01*
X547123Y-155384D01*
X547112Y-155321D01*
X547104Y-155258D01*
X547101Y-155188D01*
Y-155154D01*
X547104Y-155132D01*
X547108Y-155103D01*
X547112Y-155069D01*
X547119Y-155032D01*
X547126Y-154991D01*
X547149Y-154903D01*
X547186Y-154810D01*
X547208Y-154762D01*
X547234Y-154718D01*
X547267Y-154673D01*
X547300Y-154629D01*
X547304Y-154625D01*
X547311Y-154618D01*
X547323Y-154607D01*
X547337Y-154596D01*
X547356Y-154577D01*
X547382Y-154559D01*
X547408Y-154536D01*
X547441Y-154514D01*
X547478Y-154492D01*
X547515Y-154470D01*
X547604Y-154429D01*
X547707Y-154396D01*
X547763Y-154385D01*
X547822Y-154377D01*
X547863Y-154692D01*
D02*
G37*
G36*
X541124Y-137085D02*
X541153Y-137088D01*
X541187Y-137092D01*
X541227Y-137096D01*
X541268Y-137107D01*
X541361Y-137129D01*
X541453Y-137162D01*
X541501Y-137185D01*
X541549Y-137210D01*
X541594Y-137240D01*
X541638Y-137273D01*
X541642Y-137277D01*
X541649Y-137281D01*
X541657Y-137295D01*
X541671Y-137310D01*
X541690Y-137329D01*
X541708Y-137351D01*
X541731Y-137381D01*
X541749Y-137414D01*
X541771Y-137447D01*
X541793Y-137488D01*
X541834Y-137577D01*
X541867Y-137680D01*
X541879Y-137736D01*
X541886Y-137795D01*
X541557Y-137821D01*
Y-137817D01*
Y-137810D01*
X541553Y-137799D01*
X541549Y-137780D01*
X541538Y-137740D01*
X541523Y-137684D01*
X541501Y-137628D01*
X541472Y-137566D01*
X541435Y-137510D01*
X541390Y-137458D01*
X541383Y-137455D01*
X541368Y-137440D01*
X541338Y-137421D01*
X541298Y-137399D01*
X541253Y-137377D01*
X541198Y-137358D01*
X541135Y-137344D01*
X541065Y-137340D01*
X541042D01*
X541028Y-137344D01*
X540983Y-137347D01*
X540931Y-137362D01*
X540869Y-137381D01*
X540806Y-137410D01*
X540739Y-137455D01*
X540709Y-137480D01*
X540680Y-137510D01*
X540676Y-137514D01*
X540672Y-137517D01*
X540665Y-137529D01*
X540654Y-137540D01*
X540628Y-137580D01*
X540598Y-137632D01*
X540573Y-137695D01*
X540547Y-137773D01*
X540528Y-137865D01*
X540521Y-137913D01*
Y-137965D01*
Y-137969D01*
Y-137976D01*
Y-137991D01*
X540524Y-138010D01*
Y-138032D01*
X540528Y-138058D01*
X540539Y-138117D01*
X540558Y-138187D01*
X540584Y-138258D01*
X540621Y-138324D01*
X540672Y-138387D01*
Y-138391D01*
X540680Y-138394D01*
X540698Y-138413D01*
X540732Y-138439D01*
X540776Y-138468D01*
X540835Y-138494D01*
X540902Y-138520D01*
X540979Y-138539D01*
X541024Y-138546D01*
X541094D01*
X541124Y-138542D01*
X541161Y-138539D01*
X541205Y-138528D01*
X541250Y-138516D01*
X541298Y-138498D01*
X541346Y-138476D01*
X541350Y-138472D01*
X541364Y-138465D01*
X541387Y-138446D01*
X541416Y-138428D01*
X541446Y-138402D01*
X541475Y-138368D01*
X541509Y-138335D01*
X541535Y-138294D01*
X541830Y-138335D01*
X541583Y-139652D01*
X540310D01*
Y-139353D01*
X541335D01*
X541472Y-138661D01*
X541468Y-138664D01*
X541461Y-138668D01*
X541449Y-138676D01*
X541431Y-138687D01*
X541409Y-138698D01*
X541383Y-138713D01*
X541324Y-138742D01*
X541250Y-138772D01*
X541168Y-138798D01*
X541079Y-138816D01*
X541035Y-138824D01*
X540954D01*
X540931Y-138820D01*
X540902Y-138816D01*
X540869Y-138812D01*
X540832Y-138805D01*
X540791Y-138794D01*
X540702Y-138768D01*
X540654Y-138750D01*
X540606Y-138724D01*
X540558Y-138698D01*
X540510Y-138668D01*
X540465Y-138631D01*
X540421Y-138591D01*
X540417Y-138587D01*
X540410Y-138579D01*
X540399Y-138568D01*
X540384Y-138550D01*
X540365Y-138524D01*
X540347Y-138498D01*
X540325Y-138465D01*
X540302Y-138428D01*
X540284Y-138387D01*
X540262Y-138343D01*
X540243Y-138291D01*
X540225Y-138239D01*
X540210Y-138183D01*
X540199Y-138121D01*
X540191Y-138058D01*
X540188Y-137991D01*
Y-137987D01*
Y-137976D01*
Y-137958D01*
X540191Y-137932D01*
X540195Y-137902D01*
X540199Y-137869D01*
X540206Y-137828D01*
X540214Y-137788D01*
X540236Y-137691D01*
X540273Y-137592D01*
X540295Y-137540D01*
X540325Y-137492D01*
X540354Y-137440D01*
X540391Y-137392D01*
X540395Y-137388D01*
X540402Y-137377D01*
X540417Y-137362D01*
X540436Y-137344D01*
X540461Y-137321D01*
X540491Y-137292D01*
X540528Y-137266D01*
X540569Y-137236D01*
X540613Y-137207D01*
X540665Y-137181D01*
X540721Y-137155D01*
X540780Y-137129D01*
X540843Y-137110D01*
X540913Y-137096D01*
X540987Y-137085D01*
X541065Y-137081D01*
X541098D01*
X541124Y-137085D01*
D02*
G37*
G36*
X543307D02*
X543340D01*
X543381Y-137088D01*
X543425Y-137096D01*
X543477Y-137103D01*
X543584Y-137122D01*
X543695Y-137151D01*
X543806Y-137192D01*
X543858Y-137218D01*
X543910Y-137247D01*
X543914Y-137251D01*
X543921Y-137255D01*
X543936Y-137266D01*
X543951Y-137281D01*
X543973Y-137295D01*
X543999Y-137318D01*
X544028Y-137344D01*
X544058Y-137373D01*
X544088Y-137407D01*
X544121Y-137440D01*
X544187Y-137525D01*
X544250Y-137625D01*
X544306Y-137736D01*
Y-137740D01*
X544313Y-137751D01*
X544317Y-137769D01*
X544328Y-137791D01*
X544335Y-137821D01*
X544347Y-137858D01*
X544361Y-137899D01*
X544372Y-137943D01*
X544383Y-137991D01*
X544398Y-138047D01*
X544417Y-138161D01*
X544432Y-138291D01*
X544439Y-138424D01*
Y-138428D01*
Y-138443D01*
Y-138465D01*
X544435Y-138491D01*
Y-138528D01*
X544432Y-138565D01*
X544428Y-138613D01*
X544420Y-138661D01*
X544402Y-138768D01*
X544376Y-138886D01*
X544339Y-139005D01*
X544287Y-139120D01*
X544284Y-139123D01*
X544280Y-139134D01*
X544273Y-139149D01*
X544258Y-139168D01*
X544243Y-139194D01*
X544224Y-139223D01*
X544176Y-139290D01*
X544113Y-139364D01*
X544039Y-139438D01*
X543954Y-139512D01*
X543854Y-139575D01*
X543851Y-139578D01*
X543840Y-139582D01*
X543825Y-139590D01*
X543806Y-139601D01*
X543777Y-139612D01*
X543747Y-139623D01*
X543710Y-139638D01*
X543669Y-139652D01*
X543625Y-139667D01*
X543577Y-139682D01*
X543473Y-139704D01*
X543355Y-139723D01*
X543233Y-139730D01*
X543196D01*
X543170Y-139726D01*
X543137Y-139723D01*
X543096Y-139719D01*
X543055Y-139715D01*
X543007Y-139704D01*
X542907Y-139682D01*
X542796Y-139649D01*
X542741Y-139627D01*
X542689Y-139601D01*
X542637Y-139567D01*
X542585Y-139534D01*
X542582Y-139530D01*
X542574Y-139527D01*
X542559Y-139515D01*
X542541Y-139497D01*
X542522Y-139479D01*
X542496Y-139453D01*
X542471Y-139423D01*
X542441Y-139393D01*
X542411Y-139356D01*
X542382Y-139312D01*
X542348Y-139268D01*
X542319Y-139219D01*
X542293Y-139164D01*
X542263Y-139109D01*
X542241Y-139049D01*
X542219Y-138983D01*
X542552Y-138905D01*
Y-138909D01*
X542556Y-138916D01*
X542563Y-138931D01*
X542570Y-138949D01*
X542578Y-138972D01*
X542589Y-139001D01*
X542619Y-139060D01*
X542656Y-139127D01*
X542700Y-139194D01*
X542756Y-139257D01*
X542815Y-139312D01*
X542822Y-139319D01*
X542844Y-139334D01*
X542881Y-139353D01*
X542929Y-139379D01*
X542992Y-139401D01*
X543063Y-139423D01*
X543148Y-139438D01*
X543240Y-139442D01*
X543270D01*
X543288Y-139438D01*
X543314D01*
X543344Y-139434D01*
X543414Y-139423D01*
X543492Y-139408D01*
X543573Y-139382D01*
X543658Y-139345D01*
X543736Y-139297D01*
X543740D01*
X543743Y-139290D01*
X543769Y-139271D01*
X543803Y-139242D01*
X543843Y-139197D01*
X543891Y-139142D01*
X543936Y-139079D01*
X543976Y-139001D01*
X544014Y-138916D01*
Y-138912D01*
X544017Y-138905D01*
X544021Y-138894D01*
X544025Y-138875D01*
X544032Y-138853D01*
X544039Y-138827D01*
X544051Y-138764D01*
X544065Y-138690D01*
X544080Y-138609D01*
X544088Y-138520D01*
X544091Y-138424D01*
Y-138420D01*
Y-138409D01*
Y-138391D01*
Y-138368D01*
X544088Y-138343D01*
Y-138309D01*
X544084Y-138272D01*
X544080Y-138232D01*
X544069Y-138143D01*
X544051Y-138047D01*
X544028Y-137950D01*
X543999Y-137854D01*
Y-137850D01*
X543995Y-137843D01*
X543988Y-137832D01*
X543980Y-137813D01*
X543958Y-137769D01*
X543925Y-137717D01*
X543884Y-137658D01*
X543832Y-137595D01*
X543773Y-137540D01*
X543703Y-137488D01*
X543699D01*
X543692Y-137484D01*
X543680Y-137477D01*
X543666Y-137469D01*
X543647Y-137462D01*
X543625Y-137451D01*
X543573Y-137429D01*
X543507Y-137407D01*
X543433Y-137388D01*
X543351Y-137373D01*
X543266Y-137370D01*
X543240D01*
X543218Y-137373D01*
X543192D01*
X543166Y-137377D01*
X543100Y-137392D01*
X543022Y-137410D01*
X542944Y-137440D01*
X542863Y-137480D01*
X542822Y-137503D01*
X542785Y-137532D01*
X542781Y-137536D01*
X542778Y-137540D01*
X542767Y-137551D01*
X542752Y-137562D01*
X542737Y-137580D01*
X542719Y-137603D01*
X542696Y-137625D01*
X542678Y-137654D01*
X542656Y-137688D01*
X542630Y-137725D01*
X542607Y-137762D01*
X542585Y-137806D01*
X542567Y-137854D01*
X542548Y-137906D01*
X542530Y-137961D01*
X542515Y-138021D01*
X542175Y-137936D01*
Y-137932D01*
X542178Y-137917D01*
X542186Y-137895D01*
X542197Y-137865D01*
X542208Y-137832D01*
X542223Y-137791D01*
X542241Y-137747D01*
X542263Y-137699D01*
X542315Y-137595D01*
X542382Y-137492D01*
X542422Y-137440D01*
X542463Y-137388D01*
X542508Y-137344D01*
X542559Y-137299D01*
X542563Y-137295D01*
X542570Y-137288D01*
X542589Y-137281D01*
X542607Y-137266D01*
X542637Y-137247D01*
X542667Y-137229D01*
X542707Y-137210D01*
X542748Y-137192D01*
X542796Y-137170D01*
X542848Y-137151D01*
X542904Y-137133D01*
X542963Y-137114D01*
X543026Y-137099D01*
X543092Y-137092D01*
X543162Y-137085D01*
X543236Y-137081D01*
X543277D01*
X543307Y-137085D01*
D02*
G37*
G36*
X622135Y-131159D02*
X622169Y-131163D01*
X622209Y-131167D01*
X622250Y-131170D01*
X622298Y-131182D01*
X622398Y-131204D01*
X622509Y-131237D01*
X622565Y-131259D01*
X622616Y-131285D01*
X622668Y-131318D01*
X622720Y-131352D01*
X622724Y-131356D01*
X622731Y-131359D01*
X622746Y-131370D01*
X622764Y-131389D01*
X622783Y-131407D01*
X622809Y-131433D01*
X622835Y-131463D01*
X622864Y-131492D01*
X622894Y-131529D01*
X622924Y-131574D01*
X622957Y-131618D01*
X622986Y-131666D01*
X623012Y-131722D01*
X623042Y-131777D01*
X623064Y-131836D01*
X623086Y-131903D01*
X622753Y-131981D01*
Y-131977D01*
X622750Y-131970D01*
X622742Y-131955D01*
X622735Y-131936D01*
X622727Y-131914D01*
X622716Y-131885D01*
X622687Y-131825D01*
X622650Y-131759D01*
X622605Y-131692D01*
X622550Y-131629D01*
X622491Y-131574D01*
X622483Y-131566D01*
X622461Y-131552D01*
X622424Y-131533D01*
X622376Y-131507D01*
X622313Y-131485D01*
X622243Y-131463D01*
X622158Y-131448D01*
X622065Y-131444D01*
X622036D01*
X622017Y-131448D01*
X621991D01*
X621961Y-131452D01*
X621891Y-131463D01*
X621813Y-131478D01*
X621732Y-131503D01*
X621647Y-131541D01*
X621569Y-131589D01*
X621566D01*
X621562Y-131596D01*
X621536Y-131614D01*
X621503Y-131644D01*
X621462Y-131688D01*
X621414Y-131744D01*
X621370Y-131807D01*
X621329Y-131885D01*
X621292Y-131970D01*
Y-131973D01*
X621288Y-131981D01*
X621284Y-131992D01*
X621281Y-132010D01*
X621273Y-132033D01*
X621266Y-132059D01*
X621255Y-132121D01*
X621240Y-132195D01*
X621225Y-132277D01*
X621218Y-132366D01*
X621214Y-132462D01*
Y-132466D01*
Y-132477D01*
Y-132495D01*
Y-132517D01*
X621218Y-132543D01*
Y-132577D01*
X621221Y-132614D01*
X621225Y-132654D01*
X621236Y-132743D01*
X621255Y-132839D01*
X621277Y-132935D01*
X621307Y-133032D01*
Y-133035D01*
X621310Y-133043D01*
X621318Y-133054D01*
X621325Y-133072D01*
X621347Y-133117D01*
X621381Y-133168D01*
X621421Y-133228D01*
X621473Y-133291D01*
X621532Y-133346D01*
X621603Y-133398D01*
X621606D01*
X621614Y-133402D01*
X621625Y-133409D01*
X621640Y-133416D01*
X621658Y-133424D01*
X621680Y-133435D01*
X621732Y-133457D01*
X621799Y-133479D01*
X621873Y-133498D01*
X621954Y-133513D01*
X622039Y-133516D01*
X622065D01*
X622087Y-133513D01*
X622113D01*
X622139Y-133509D01*
X622206Y-133494D01*
X622283Y-133476D01*
X622361Y-133446D01*
X622442Y-133405D01*
X622483Y-133383D01*
X622520Y-133353D01*
X622524Y-133350D01*
X622528Y-133346D01*
X622539Y-133335D01*
X622553Y-133324D01*
X622568Y-133305D01*
X622587Y-133283D01*
X622609Y-133261D01*
X622627Y-133231D01*
X622650Y-133198D01*
X622676Y-133161D01*
X622698Y-133124D01*
X622720Y-133080D01*
X622739Y-133032D01*
X622757Y-132980D01*
X622776Y-132924D01*
X622790Y-132865D01*
X623131Y-132950D01*
Y-132954D01*
X623127Y-132969D01*
X623120Y-132991D01*
X623108Y-133020D01*
X623097Y-133054D01*
X623083Y-133095D01*
X623064Y-133139D01*
X623042Y-133187D01*
X622990Y-133291D01*
X622924Y-133394D01*
X622883Y-133446D01*
X622842Y-133498D01*
X622798Y-133542D01*
X622746Y-133587D01*
X622742Y-133590D01*
X622735Y-133598D01*
X622716Y-133605D01*
X622698Y-133620D01*
X622668Y-133638D01*
X622639Y-133657D01*
X622598Y-133675D01*
X622557Y-133694D01*
X622509Y-133716D01*
X622457Y-133735D01*
X622402Y-133753D01*
X622343Y-133772D01*
X622280Y-133786D01*
X622213Y-133794D01*
X622143Y-133801D01*
X622069Y-133805D01*
X622028D01*
X621999Y-133801D01*
X621965D01*
X621924Y-133798D01*
X621880Y-133790D01*
X621828Y-133783D01*
X621721Y-133764D01*
X621610Y-133735D01*
X621499Y-133694D01*
X621447Y-133668D01*
X621395Y-133638D01*
X621392Y-133635D01*
X621384Y-133631D01*
X621370Y-133620D01*
X621355Y-133605D01*
X621333Y-133590D01*
X621307Y-133568D01*
X621277Y-133542D01*
X621247Y-133513D01*
X621218Y-133479D01*
X621184Y-133446D01*
X621118Y-133361D01*
X621055Y-133261D01*
X620999Y-133150D01*
Y-133146D01*
X620992Y-133135D01*
X620988Y-133117D01*
X620977Y-133095D01*
X620970Y-133065D01*
X620959Y-133028D01*
X620944Y-132987D01*
X620933Y-132943D01*
X620922Y-132895D01*
X620907Y-132839D01*
X620889Y-132724D01*
X620874Y-132595D01*
X620866Y-132462D01*
Y-132458D01*
Y-132443D01*
Y-132421D01*
X620870Y-132395D01*
Y-132358D01*
X620874Y-132321D01*
X620877Y-132273D01*
X620885Y-132225D01*
X620903Y-132118D01*
X620929Y-131999D01*
X620966Y-131881D01*
X621018Y-131766D01*
X621022Y-131763D01*
X621025Y-131751D01*
X621033Y-131737D01*
X621048Y-131718D01*
X621062Y-131692D01*
X621081Y-131663D01*
X621129Y-131596D01*
X621192Y-131522D01*
X621266Y-131448D01*
X621351Y-131374D01*
X621451Y-131311D01*
X621455Y-131307D01*
X621466Y-131304D01*
X621481Y-131296D01*
X621499Y-131285D01*
X621529Y-131274D01*
X621558Y-131263D01*
X621595Y-131248D01*
X621636Y-131233D01*
X621680Y-131219D01*
X621728Y-131204D01*
X621832Y-131182D01*
X621950Y-131163D01*
X622073Y-131156D01*
X622110D01*
X622135Y-131159D01*
D02*
G37*
G36*
X625099Y-131481D02*
X625095Y-131485D01*
X625088Y-131492D01*
X625073Y-131507D01*
X625058Y-131529D01*
X625036Y-131555D01*
X625007Y-131585D01*
X624977Y-131622D01*
X624944Y-131666D01*
X624910Y-131711D01*
X624870Y-131763D01*
X624829Y-131822D01*
X624788Y-131881D01*
X624744Y-131948D01*
X624699Y-132018D01*
X624655Y-132096D01*
X624611Y-132173D01*
X624607Y-132177D01*
X624600Y-132192D01*
X624588Y-132214D01*
X624570Y-132247D01*
X624551Y-132288D01*
X624529Y-132332D01*
X624503Y-132384D01*
X624477Y-132443D01*
X624448Y-132510D01*
X624415Y-132577D01*
X624385Y-132650D01*
X624355Y-132728D01*
X624296Y-132887D01*
X624241Y-133057D01*
Y-133061D01*
X624237Y-133072D01*
X624233Y-133091D01*
X624226Y-133113D01*
X624219Y-133143D01*
X624211Y-133180D01*
X624200Y-133220D01*
X624193Y-133265D01*
X624182Y-133317D01*
X624170Y-133372D01*
X624152Y-133490D01*
X624133Y-133620D01*
X624122Y-133760D01*
X623800D01*
Y-133757D01*
Y-133746D01*
Y-133731D01*
X623804Y-133709D01*
Y-133679D01*
X623808Y-133642D01*
X623811Y-133601D01*
X623815Y-133557D01*
X623823Y-133505D01*
X623830Y-133453D01*
X623841Y-133390D01*
X623852Y-133328D01*
X623863Y-133261D01*
X623878Y-133187D01*
X623915Y-133035D01*
Y-133032D01*
X623919Y-133017D01*
X623926Y-132995D01*
X623937Y-132961D01*
X623948Y-132924D01*
X623963Y-132880D01*
X623978Y-132828D01*
X624000Y-132773D01*
X624022Y-132710D01*
X624045Y-132647D01*
X624100Y-132506D01*
X624167Y-132358D01*
X624241Y-132210D01*
X624244Y-132206D01*
X624252Y-132192D01*
X624263Y-132173D01*
X624278Y-132144D01*
X624296Y-132110D01*
X624322Y-132070D01*
X624348Y-132025D01*
X624378Y-131977D01*
X624448Y-131870D01*
X624522Y-131759D01*
X624607Y-131644D01*
X624696Y-131537D01*
X623442D01*
Y-131233D01*
X625099D01*
Y-131481D01*
D02*
G37*
G36*
X622133Y-139821D02*
X622167Y-139824D01*
X622207Y-139828D01*
X622248Y-139832D01*
X622296Y-139843D01*
X622396Y-139865D01*
X622507Y-139899D01*
X622563Y-139921D01*
X622614Y-139947D01*
X622666Y-139980D01*
X622718Y-140013D01*
X622722Y-140017D01*
X622729Y-140021D01*
X622744Y-140032D01*
X622762Y-140050D01*
X622781Y-140069D01*
X622807Y-140095D01*
X622833Y-140124D01*
X622862Y-140154D01*
X622892Y-140191D01*
X622922Y-140235D01*
X622955Y-140280D01*
X622985Y-140328D01*
X623010Y-140383D01*
X623040Y-140439D01*
X623062Y-140498D01*
X623084Y-140565D01*
X622751Y-140642D01*
Y-140638D01*
X622748Y-140631D01*
X622740Y-140616D01*
X622733Y-140598D01*
X622725Y-140576D01*
X622714Y-140546D01*
X622685Y-140487D01*
X622648Y-140420D01*
X622603Y-140354D01*
X622548Y-140291D01*
X622489Y-140235D01*
X622481Y-140228D01*
X622459Y-140213D01*
X622422Y-140194D01*
X622374Y-140169D01*
X622311Y-140146D01*
X622241Y-140124D01*
X622156Y-140109D01*
X622063Y-140106D01*
X622034D01*
X622015Y-140109D01*
X621989D01*
X621960Y-140113D01*
X621889Y-140124D01*
X621812Y-140139D01*
X621730Y-140165D01*
X621645Y-140202D01*
X621567Y-140250D01*
X621564D01*
X621560Y-140257D01*
X621534Y-140276D01*
X621501Y-140305D01*
X621460Y-140350D01*
X621412Y-140405D01*
X621368Y-140468D01*
X621327Y-140546D01*
X621290Y-140631D01*
Y-140635D01*
X621286Y-140642D01*
X621282Y-140653D01*
X621279Y-140672D01*
X621271Y-140694D01*
X621264Y-140720D01*
X621253Y-140783D01*
X621238Y-140857D01*
X621223Y-140938D01*
X621216Y-141027D01*
X621212Y-141123D01*
Y-141127D01*
Y-141138D01*
Y-141156D01*
Y-141179D01*
X621216Y-141205D01*
Y-141238D01*
X621220Y-141275D01*
X621223Y-141316D01*
X621234Y-141404D01*
X621253Y-141501D01*
X621275Y-141597D01*
X621305Y-141693D01*
Y-141697D01*
X621308Y-141704D01*
X621316Y-141715D01*
X621323Y-141734D01*
X621345Y-141778D01*
X621379Y-141830D01*
X621419Y-141889D01*
X621471Y-141952D01*
X621530Y-142008D01*
X621601Y-142059D01*
X621604D01*
X621612Y-142063D01*
X621623Y-142070D01*
X621638Y-142078D01*
X621656Y-142085D01*
X621678Y-142096D01*
X621730Y-142119D01*
X621797Y-142141D01*
X621871Y-142159D01*
X621952Y-142174D01*
X622037Y-142178D01*
X622063D01*
X622085Y-142174D01*
X622111D01*
X622137Y-142170D01*
X622204Y-142156D01*
X622282Y-142137D01*
X622359Y-142107D01*
X622441Y-142067D01*
X622481Y-142044D01*
X622518Y-142015D01*
X622522Y-142011D01*
X622526Y-142008D01*
X622537Y-141996D01*
X622552Y-141985D01*
X622566Y-141967D01*
X622585Y-141945D01*
X622607Y-141922D01*
X622626Y-141893D01*
X622648Y-141859D01*
X622674Y-141823D01*
X622696Y-141786D01*
X622718Y-141741D01*
X622737Y-141693D01*
X622755Y-141641D01*
X622774Y-141586D01*
X622788Y-141526D01*
X623129Y-141612D01*
Y-141615D01*
X623125Y-141630D01*
X623118Y-141652D01*
X623107Y-141682D01*
X623096Y-141715D01*
X623081Y-141756D01*
X623062Y-141800D01*
X623040Y-141848D01*
X622988Y-141952D01*
X622922Y-142056D01*
X622881Y-142107D01*
X622840Y-142159D01*
X622796Y-142204D01*
X622744Y-142248D01*
X622740Y-142252D01*
X622733Y-142259D01*
X622714Y-142266D01*
X622696Y-142281D01*
X622666Y-142300D01*
X622637Y-142318D01*
X622596Y-142337D01*
X622555Y-142355D01*
X622507Y-142377D01*
X622455Y-142396D01*
X622400Y-142414D01*
X622341Y-142433D01*
X622278Y-142448D01*
X622211Y-142455D01*
X622141Y-142463D01*
X622067Y-142466D01*
X622026D01*
X621997Y-142463D01*
X621963D01*
X621923Y-142459D01*
X621878Y-142452D01*
X621826Y-142444D01*
X621719Y-142426D01*
X621608Y-142396D01*
X621497Y-142355D01*
X621445Y-142329D01*
X621393Y-142300D01*
X621390Y-142296D01*
X621382Y-142292D01*
X621368Y-142281D01*
X621353Y-142266D01*
X621331Y-142252D01*
X621305Y-142229D01*
X621275Y-142204D01*
X621245Y-142174D01*
X621216Y-142141D01*
X621183Y-142107D01*
X621116Y-142022D01*
X621053Y-141922D01*
X620998Y-141811D01*
Y-141808D01*
X620990Y-141797D01*
X620987Y-141778D01*
X620975Y-141756D01*
X620968Y-141726D01*
X620957Y-141689D01*
X620942Y-141649D01*
X620931Y-141604D01*
X620920Y-141556D01*
X620905Y-141501D01*
X620887Y-141386D01*
X620872Y-141256D01*
X620864Y-141123D01*
Y-141120D01*
Y-141105D01*
Y-141083D01*
X620868Y-141057D01*
Y-141020D01*
X620872Y-140983D01*
X620876Y-140935D01*
X620883Y-140886D01*
X620901Y-140779D01*
X620927Y-140661D01*
X620964Y-140542D01*
X621016Y-140428D01*
X621020Y-140424D01*
X621024Y-140413D01*
X621031Y-140398D01*
X621046Y-140380D01*
X621061Y-140354D01*
X621079Y-140324D01*
X621127Y-140257D01*
X621190Y-140183D01*
X621264Y-140109D01*
X621349Y-140035D01*
X621449Y-139972D01*
X621453Y-139969D01*
X621464Y-139965D01*
X621479Y-139958D01*
X621497Y-139947D01*
X621527Y-139936D01*
X621556Y-139924D01*
X621593Y-139910D01*
X621634Y-139895D01*
X621678Y-139880D01*
X621727Y-139865D01*
X621830Y-139843D01*
X621948Y-139824D01*
X622071Y-139817D01*
X622108D01*
X622133Y-139821D01*
D02*
G37*
G36*
X624305Y-139854D02*
X624335Y-139858D01*
X624368Y-139862D01*
X624405Y-139865D01*
X624442Y-139876D01*
X624531Y-139899D01*
X624620Y-139932D01*
X624664Y-139954D01*
X624709Y-139980D01*
X624749Y-140013D01*
X624790Y-140047D01*
X624794Y-140050D01*
X624797Y-140054D01*
X624809Y-140065D01*
X624823Y-140080D01*
X624838Y-140102D01*
X624857Y-140124D01*
X624894Y-140180D01*
X624931Y-140250D01*
X624964Y-140331D01*
X624990Y-140424D01*
X624994Y-140472D01*
X624997Y-140524D01*
Y-140527D01*
Y-140531D01*
Y-140553D01*
X624994Y-140587D01*
X624986Y-140627D01*
X624975Y-140679D01*
X624957Y-140731D01*
X624934Y-140783D01*
X624901Y-140835D01*
X624897Y-140842D01*
X624883Y-140857D01*
X624860Y-140879D01*
X624831Y-140909D01*
X624790Y-140942D01*
X624742Y-140975D01*
X624686Y-141008D01*
X624620Y-141038D01*
X624624D01*
X624631Y-141042D01*
X624642Y-141045D01*
X624657Y-141053D01*
X624701Y-141071D01*
X624753Y-141097D01*
X624809Y-141134D01*
X624868Y-141175D01*
X624923Y-141227D01*
X624975Y-141286D01*
Y-141290D01*
X624979Y-141293D01*
X624994Y-141316D01*
X625016Y-141353D01*
X625038Y-141401D01*
X625060Y-141460D01*
X625082Y-141530D01*
X625097Y-141608D01*
X625101Y-141693D01*
Y-141697D01*
Y-141708D01*
Y-141726D01*
X625097Y-141748D01*
X625094Y-141774D01*
X625090Y-141808D01*
X625082Y-141845D01*
X625071Y-141885D01*
X625045Y-141971D01*
X625027Y-142019D01*
X625001Y-142063D01*
X624975Y-142111D01*
X624945Y-142156D01*
X624908Y-142200D01*
X624868Y-142244D01*
X624864Y-142248D01*
X624857Y-142255D01*
X624846Y-142266D01*
X624827Y-142278D01*
X624801Y-142296D01*
X624775Y-142315D01*
X624742Y-142333D01*
X624705Y-142355D01*
X624664Y-142377D01*
X624616Y-142396D01*
X624564Y-142414D01*
X624513Y-142433D01*
X624453Y-142444D01*
X624391Y-142455D01*
X624328Y-142463D01*
X624257Y-142466D01*
X624220D01*
X624194Y-142463D01*
X624161Y-142459D01*
X624124Y-142455D01*
X624083Y-142448D01*
X624039Y-142437D01*
X623939Y-142411D01*
X623887Y-142392D01*
X623839Y-142374D01*
X623787Y-142348D01*
X623736Y-142318D01*
X623688Y-142285D01*
X623643Y-142244D01*
X623639Y-142241D01*
X623632Y-142233D01*
X623621Y-142222D01*
X623606Y-142204D01*
X623591Y-142181D01*
X623569Y-142156D01*
X623551Y-142126D01*
X623528Y-142089D01*
X623506Y-142052D01*
X623488Y-142008D01*
X623451Y-141915D01*
X623436Y-141859D01*
X623425Y-141804D01*
X623417Y-141745D01*
X623414Y-141686D01*
Y-141682D01*
Y-141674D01*
Y-141660D01*
X623417Y-141645D01*
Y-141623D01*
X623421Y-141597D01*
X623428Y-141538D01*
X623443Y-141471D01*
X623465Y-141404D01*
X623499Y-141334D01*
X623539Y-141268D01*
Y-141264D01*
X623547Y-141260D01*
X623562Y-141242D01*
X623591Y-141212D01*
X623632Y-141175D01*
X623684Y-141138D01*
X623747Y-141097D01*
X623817Y-141064D01*
X623902Y-141038D01*
X623898D01*
X623895Y-141034D01*
X623884Y-141031D01*
X623869Y-141023D01*
X623836Y-141008D01*
X623791Y-140986D01*
X623743Y-140957D01*
X623695Y-140920D01*
X623651Y-140879D01*
X623610Y-140835D01*
X623606Y-140827D01*
X623595Y-140812D01*
X623580Y-140783D01*
X623565Y-140746D01*
X623547Y-140698D01*
X623532Y-140642D01*
X623521Y-140579D01*
X623517Y-140513D01*
Y-140509D01*
Y-140502D01*
Y-140487D01*
X623521Y-140465D01*
X623525Y-140442D01*
X623528Y-140413D01*
X623543Y-140350D01*
X623565Y-140276D01*
X623602Y-140198D01*
X623625Y-140157D01*
X623651Y-140117D01*
X623684Y-140080D01*
X623717Y-140043D01*
X623721Y-140039D01*
X623728Y-140035D01*
X623739Y-140024D01*
X623754Y-140013D01*
X623773Y-139998D01*
X623799Y-139984D01*
X623828Y-139965D01*
X623858Y-139947D01*
X623895Y-139928D01*
X623935Y-139910D01*
X623980Y-139895D01*
X624028Y-139880D01*
X624131Y-139858D01*
X624191Y-139854D01*
X624250Y-139850D01*
X624283D01*
X624305Y-139854D01*
D02*
G37*
G36*
X206064Y-377842D02*
X207721D01*
Y-378097D01*
X206064Y-379270D01*
X205775D01*
Y-378156D01*
X205161D01*
Y-377842D01*
X205775D01*
Y-377494D01*
X206064D01*
Y-377842D01*
D02*
G37*
G36*
Y-379832D02*
X207721D01*
Y-380088D01*
X206064Y-381260D01*
X205775D01*
Y-380147D01*
X205161D01*
Y-379832D01*
X205775D01*
Y-379485D01*
X206064D01*
Y-379832D01*
D02*
G37*
G36*
X206056Y-381782D02*
X205997Y-381797D01*
X205941Y-381816D01*
X205890Y-381834D01*
X205841Y-381853D01*
X205797Y-381875D01*
X205760Y-381897D01*
X205723Y-381923D01*
X205690Y-381945D01*
X205660Y-381963D01*
X205638Y-381986D01*
X205616Y-382004D01*
X205597Y-382019D01*
X205586Y-382034D01*
X205575Y-382045D01*
X205571Y-382049D01*
X205568Y-382052D01*
X205538Y-382089D01*
X205516Y-382130D01*
X205475Y-382211D01*
X205446Y-382289D01*
X205427Y-382367D01*
X205412Y-382433D01*
X205409Y-382459D01*
Y-382485D01*
X205405Y-382507D01*
Y-382533D01*
X205409Y-382618D01*
X205423Y-382700D01*
X205442Y-382774D01*
X205464Y-382840D01*
X205486Y-382892D01*
X205497Y-382914D01*
X205505Y-382933D01*
X205512Y-382948D01*
X205520Y-382959D01*
X205523Y-382966D01*
Y-382970D01*
X205575Y-383040D01*
X205631Y-383099D01*
X205694Y-383151D01*
X205753Y-383192D01*
X205804Y-383225D01*
X205849Y-383247D01*
X205867Y-383255D01*
X205878Y-383262D01*
X205886Y-383266D01*
X205890D01*
X205986Y-383295D01*
X206082Y-383318D01*
X206178Y-383336D01*
X206267Y-383347D01*
X206308Y-383351D01*
X206345Y-383355D01*
X206378D01*
X206404Y-383358D01*
X206426D01*
X206445D01*
X206456D01*
X206459D01*
X206556Y-383355D01*
X206644Y-383347D01*
X206726Y-383332D01*
X206800Y-383318D01*
X206863Y-383307D01*
X206889Y-383299D01*
X206911Y-383292D01*
X206929Y-383288D01*
X206940Y-383284D01*
X206948Y-383281D01*
X206951D01*
X207037Y-383244D01*
X207114Y-383203D01*
X207177Y-383159D01*
X207233Y-383110D01*
X207277Y-383070D01*
X207307Y-383036D01*
X207325Y-383011D01*
X207333Y-383007D01*
Y-383003D01*
X207381Y-382926D01*
X207418Y-382840D01*
X207444Y-382759D01*
X207458Y-382681D01*
X207470Y-382611D01*
X207473Y-382581D01*
Y-382556D01*
X207477Y-382537D01*
Y-382507D01*
X207473Y-382415D01*
X207458Y-382330D01*
X207436Y-382259D01*
X207414Y-382197D01*
X207388Y-382149D01*
X207370Y-382112D01*
X207355Y-382089D01*
X207347Y-382082D01*
X207292Y-382023D01*
X207229Y-381967D01*
X207162Y-381923D01*
X207096Y-381886D01*
X207037Y-381856D01*
X207007Y-381845D01*
X206985Y-381838D01*
X206966Y-381830D01*
X206951Y-381823D01*
X206944Y-381819D01*
X206940D01*
X207018Y-381486D01*
X207085Y-381508D01*
X207144Y-381531D01*
X207199Y-381560D01*
X207255Y-381586D01*
X207303Y-381616D01*
X207347Y-381649D01*
X207392Y-381679D01*
X207429Y-381708D01*
X207458Y-381738D01*
X207488Y-381764D01*
X207514Y-381790D01*
X207532Y-381808D01*
X207551Y-381827D01*
X207562Y-381841D01*
X207566Y-381849D01*
X207569Y-381853D01*
X207603Y-381904D01*
X207636Y-381956D01*
X207662Y-382008D01*
X207684Y-382063D01*
X207717Y-382174D01*
X207740Y-382274D01*
X207751Y-382322D01*
X207754Y-382363D01*
X207758Y-382404D01*
X207762Y-382437D01*
X207766Y-382463D01*
Y-382500D01*
X207758Y-382622D01*
X207740Y-382740D01*
X207717Y-382844D01*
X207703Y-382892D01*
X207688Y-382937D01*
X207673Y-382977D01*
X207658Y-383014D01*
X207647Y-383044D01*
X207636Y-383073D01*
X207625Y-383092D01*
X207617Y-383107D01*
X207614Y-383118D01*
X207610Y-383122D01*
X207547Y-383222D01*
X207473Y-383307D01*
X207399Y-383381D01*
X207325Y-383443D01*
X207259Y-383492D01*
X207229Y-383510D01*
X207203Y-383525D01*
X207185Y-383540D01*
X207170Y-383547D01*
X207159Y-383551D01*
X207155Y-383555D01*
X207040Y-383606D01*
X206922Y-383643D01*
X206803Y-383669D01*
X206696Y-383688D01*
X206648Y-383695D01*
X206600Y-383699D01*
X206563Y-383702D01*
X206526D01*
X206500Y-383706D01*
X206478D01*
X206463D01*
X206459D01*
X206326Y-383699D01*
X206197Y-383684D01*
X206082Y-383665D01*
X206027Y-383651D01*
X205978Y-383640D01*
X205934Y-383629D01*
X205893Y-383614D01*
X205856Y-383603D01*
X205827Y-383595D01*
X205804Y-383584D01*
X205786Y-383580D01*
X205775Y-383573D01*
X205771D01*
X205660Y-383518D01*
X205560Y-383455D01*
X205475Y-383388D01*
X205442Y-383355D01*
X205409Y-383325D01*
X205379Y-383295D01*
X205353Y-383266D01*
X205331Y-383240D01*
X205316Y-383218D01*
X205301Y-383203D01*
X205290Y-383188D01*
X205287Y-383181D01*
X205283Y-383177D01*
X205253Y-383125D01*
X205227Y-383073D01*
X205187Y-382962D01*
X205157Y-382852D01*
X205138Y-382744D01*
X205131Y-382692D01*
X205124Y-382648D01*
X205120Y-382607D01*
Y-382574D01*
X205116Y-382544D01*
Y-382504D01*
X205120Y-382430D01*
X205127Y-382359D01*
X205135Y-382293D01*
X205150Y-382230D01*
X205168Y-382171D01*
X205187Y-382115D01*
X205205Y-382063D01*
X205227Y-382015D01*
X205246Y-381975D01*
X205264Y-381934D01*
X205283Y-381904D01*
X205301Y-381875D01*
X205316Y-381856D01*
X205324Y-381838D01*
X205331Y-381830D01*
X205335Y-381827D01*
X205379Y-381775D01*
X205423Y-381730D01*
X205475Y-381690D01*
X205527Y-381649D01*
X205631Y-381582D01*
X205734Y-381531D01*
X205782Y-381508D01*
X205827Y-381490D01*
X205867Y-381475D01*
X205901Y-381464D01*
X205930Y-381453D01*
X205953Y-381446D01*
X205967Y-381442D01*
X205971D01*
X206056Y-381782D01*
D02*
G37*
G36*
X209342Y-365698D02*
X209405Y-365706D01*
X209468Y-365717D01*
X209523Y-365732D01*
X209575Y-365750D01*
X209627Y-365769D01*
X209671Y-365791D01*
X209712Y-365809D01*
X209749Y-365831D01*
X209782Y-365854D01*
X209808Y-365872D01*
X209834Y-365891D01*
X209853Y-365905D01*
X209864Y-365917D01*
X209871Y-365924D01*
X209875Y-365928D01*
X209915Y-365972D01*
X209952Y-366017D01*
X209982Y-366065D01*
X210008Y-366113D01*
X210034Y-366161D01*
X210052Y-366209D01*
X210078Y-366298D01*
X210089Y-366338D01*
X210097Y-366375D01*
X210101Y-366409D01*
X210104Y-366438D01*
X210108Y-366460D01*
Y-366542D01*
X210101Y-366586D01*
X210082Y-366675D01*
X210056Y-366757D01*
X210027Y-366830D01*
X209997Y-366890D01*
X209982Y-366916D01*
X209971Y-366938D01*
X209960Y-366956D01*
X209952Y-366967D01*
X209949Y-366975D01*
X209945Y-366979D01*
X210637Y-366842D01*
Y-365817D01*
X210937D01*
Y-367090D01*
X209619Y-367337D01*
X209579Y-367041D01*
X209619Y-367016D01*
X209653Y-366982D01*
X209686Y-366953D01*
X209712Y-366923D01*
X209731Y-366893D01*
X209749Y-366871D01*
X209756Y-366856D01*
X209760Y-366853D01*
X209782Y-366805D01*
X209801Y-366757D01*
X209812Y-366712D01*
X209823Y-366668D01*
X209827Y-366631D01*
X209830Y-366601D01*
Y-366531D01*
X209823Y-366486D01*
X209805Y-366409D01*
X209779Y-366342D01*
X209753Y-366283D01*
X209723Y-366238D01*
X209697Y-366205D01*
X209679Y-366187D01*
X209675Y-366179D01*
X209671D01*
X209608Y-366127D01*
X209542Y-366090D01*
X209472Y-366065D01*
X209401Y-366046D01*
X209342Y-366035D01*
X209316Y-366031D01*
X209294D01*
X209275Y-366028D01*
X209261D01*
X209253D01*
X209249D01*
X209198D01*
X209150Y-366035D01*
X209057Y-366054D01*
X208979Y-366079D01*
X208916Y-366105D01*
X208865Y-366135D01*
X208824Y-366161D01*
X208813Y-366172D01*
X208802Y-366179D01*
X208798Y-366183D01*
X208794Y-366187D01*
X208765Y-366216D01*
X208739Y-366246D01*
X208695Y-366313D01*
X208665Y-366375D01*
X208646Y-366438D01*
X208632Y-366490D01*
X208628Y-366534D01*
X208624Y-366549D01*
Y-366571D01*
X208628Y-366642D01*
X208643Y-366705D01*
X208661Y-366760D01*
X208683Y-366805D01*
X208706Y-366845D01*
X208724Y-366875D01*
X208739Y-366890D01*
X208743Y-366897D01*
X208794Y-366941D01*
X208850Y-366979D01*
X208913Y-367008D01*
X208968Y-367030D01*
X209024Y-367045D01*
X209065Y-367056D01*
X209083Y-367060D01*
X209094Y-367064D01*
X209102D01*
X209105D01*
X209079Y-367393D01*
X209020Y-367386D01*
X208965Y-367374D01*
X208861Y-367341D01*
X208772Y-367300D01*
X208732Y-367278D01*
X208698Y-367256D01*
X208665Y-367237D01*
X208635Y-367215D01*
X208613Y-367197D01*
X208595Y-367178D01*
X208580Y-367163D01*
X208565Y-367156D01*
X208561Y-367149D01*
X208558Y-367145D01*
X208524Y-367101D01*
X208495Y-367056D01*
X208469Y-367008D01*
X208447Y-366960D01*
X208413Y-366867D01*
X208391Y-366775D01*
X208380Y-366734D01*
X208376Y-366694D01*
X208373Y-366660D01*
X208369Y-366631D01*
X208365Y-366605D01*
Y-366571D01*
X208369Y-366494D01*
X208380Y-366420D01*
X208395Y-366350D01*
X208413Y-366287D01*
X208439Y-366227D01*
X208465Y-366172D01*
X208491Y-366120D01*
X208521Y-366076D01*
X208550Y-366035D01*
X208576Y-365998D01*
X208606Y-365968D01*
X208628Y-365943D01*
X208646Y-365924D01*
X208661Y-365909D01*
X208672Y-365902D01*
X208676Y-365898D01*
X208724Y-365861D01*
X208776Y-365831D01*
X208824Y-365802D01*
X208876Y-365780D01*
X208976Y-365743D01*
X209072Y-365721D01*
X209113Y-365713D01*
X209153Y-365706D01*
X209187Y-365702D01*
X209216Y-365698D01*
X209242Y-365695D01*
X209261D01*
X209272D01*
X209275D01*
X209342Y-365698D01*
D02*
G37*
G36*
X209312Y-368063D02*
X210970D01*
Y-368318D01*
X209312Y-369491D01*
X209024D01*
Y-368377D01*
X208410D01*
Y-368063D01*
X209024D01*
Y-367715D01*
X209312D01*
Y-368063D01*
D02*
G37*
G36*
X209305Y-370012D02*
X209246Y-370027D01*
X209190Y-370046D01*
X209138Y-370064D01*
X209090Y-370083D01*
X209046Y-370105D01*
X209009Y-370127D01*
X208972Y-370153D01*
X208939Y-370175D01*
X208909Y-370194D01*
X208887Y-370216D01*
X208865Y-370234D01*
X208846Y-370249D01*
X208835Y-370264D01*
X208824Y-370275D01*
X208820Y-370279D01*
X208817Y-370283D01*
X208787Y-370320D01*
X208765Y-370360D01*
X208724Y-370442D01*
X208695Y-370519D01*
X208676Y-370597D01*
X208661Y-370664D01*
X208658Y-370690D01*
Y-370715D01*
X208654Y-370738D01*
Y-370764D01*
X208658Y-370849D01*
X208672Y-370930D01*
X208691Y-371004D01*
X208713Y-371071D01*
X208735Y-371123D01*
X208746Y-371145D01*
X208754Y-371163D01*
X208761Y-371178D01*
X208769Y-371189D01*
X208772Y-371197D01*
Y-371200D01*
X208824Y-371270D01*
X208879Y-371330D01*
X208942Y-371381D01*
X209002Y-371422D01*
X209053Y-371456D01*
X209098Y-371478D01*
X209116Y-371485D01*
X209127Y-371493D01*
X209135Y-371496D01*
X209138D01*
X209235Y-371526D01*
X209331Y-371548D01*
X209427Y-371567D01*
X209516Y-371578D01*
X209557Y-371581D01*
X209594Y-371585D01*
X209627D01*
X209653Y-371589D01*
X209675D01*
X209694D01*
X209705D01*
X209708D01*
X209805Y-371585D01*
X209893Y-371578D01*
X209975Y-371563D01*
X210049Y-371548D01*
X210112Y-371537D01*
X210138Y-371530D01*
X210160Y-371522D01*
X210178Y-371518D01*
X210189Y-371515D01*
X210197Y-371511D01*
X210200D01*
X210285Y-371474D01*
X210363Y-371433D01*
X210426Y-371389D01*
X210482Y-371341D01*
X210526Y-371300D01*
X210556Y-371267D01*
X210574Y-371241D01*
X210581Y-371237D01*
Y-371234D01*
X210630Y-371156D01*
X210667Y-371071D01*
X210693Y-370989D01*
X210707Y-370912D01*
X210718Y-370841D01*
X210722Y-370812D01*
Y-370786D01*
X210726Y-370767D01*
Y-370738D01*
X210722Y-370645D01*
X210707Y-370560D01*
X210685Y-370490D01*
X210663Y-370427D01*
X210637Y-370379D01*
X210618Y-370342D01*
X210604Y-370320D01*
X210596Y-370312D01*
X210541Y-370253D01*
X210478Y-370198D01*
X210411Y-370153D01*
X210345Y-370116D01*
X210285Y-370087D01*
X210256Y-370075D01*
X210234Y-370068D01*
X210215Y-370061D01*
X210200Y-370053D01*
X210193Y-370050D01*
X210189D01*
X210267Y-369717D01*
X210334Y-369739D01*
X210393Y-369761D01*
X210448Y-369791D01*
X210504Y-369816D01*
X210552Y-369846D01*
X210596Y-369879D01*
X210641Y-369909D01*
X210678Y-369938D01*
X210707Y-369968D01*
X210737Y-369994D01*
X210763Y-370020D01*
X210781Y-370038D01*
X210800Y-370057D01*
X210811Y-370072D01*
X210815Y-370079D01*
X210818Y-370083D01*
X210852Y-370135D01*
X210885Y-370186D01*
X210911Y-370238D01*
X210933Y-370294D01*
X210966Y-370405D01*
X210988Y-370505D01*
X211000Y-370553D01*
X211003Y-370593D01*
X211007Y-370634D01*
X211011Y-370667D01*
X211014Y-370693D01*
Y-370730D01*
X211007Y-370852D01*
X210988Y-370971D01*
X210966Y-371074D01*
X210951Y-371123D01*
X210937Y-371167D01*
X210922Y-371208D01*
X210907Y-371245D01*
X210896Y-371274D01*
X210885Y-371304D01*
X210874Y-371322D01*
X210866Y-371337D01*
X210863Y-371348D01*
X210859Y-371352D01*
X210796Y-371452D01*
X210722Y-371537D01*
X210648Y-371611D01*
X210574Y-371674D01*
X210507Y-371722D01*
X210478Y-371740D01*
X210452Y-371755D01*
X210434Y-371770D01*
X210419Y-371777D01*
X210408Y-371781D01*
X210404Y-371785D01*
X210289Y-371837D01*
X210171Y-371874D01*
X210052Y-371900D01*
X209945Y-371918D01*
X209897Y-371925D01*
X209849Y-371929D01*
X209812Y-371933D01*
X209775D01*
X209749Y-371936D01*
X209727D01*
X209712D01*
X209708D01*
X209575Y-371929D01*
X209446Y-371914D01*
X209331Y-371896D01*
X209275Y-371881D01*
X209227Y-371870D01*
X209183Y-371859D01*
X209142Y-371844D01*
X209105Y-371833D01*
X209076Y-371826D01*
X209053Y-371814D01*
X209035Y-371811D01*
X209024Y-371803D01*
X209020D01*
X208909Y-371748D01*
X208809Y-371685D01*
X208724Y-371618D01*
X208691Y-371585D01*
X208658Y-371555D01*
X208628Y-371526D01*
X208602Y-371496D01*
X208580Y-371470D01*
X208565Y-371448D01*
X208550Y-371433D01*
X208539Y-371418D01*
X208535Y-371411D01*
X208532Y-371407D01*
X208502Y-371356D01*
X208476Y-371304D01*
X208436Y-371193D01*
X208406Y-371082D01*
X208387Y-370974D01*
X208380Y-370923D01*
X208373Y-370878D01*
X208369Y-370838D01*
Y-370804D01*
X208365Y-370775D01*
Y-370734D01*
X208369Y-370660D01*
X208376Y-370590D01*
X208384Y-370523D01*
X208399Y-370460D01*
X208417Y-370401D01*
X208436Y-370345D01*
X208454Y-370294D01*
X208476Y-370246D01*
X208495Y-370205D01*
X208513Y-370164D01*
X208532Y-370135D01*
X208550Y-370105D01*
X208565Y-370087D01*
X208572Y-370068D01*
X208580Y-370061D01*
X208583Y-370057D01*
X208628Y-370005D01*
X208672Y-369961D01*
X208724Y-369920D01*
X208776Y-369879D01*
X208879Y-369813D01*
X208983Y-369761D01*
X209031Y-369739D01*
X209076Y-369720D01*
X209116Y-369705D01*
X209150Y-369694D01*
X209179Y-369683D01*
X209201Y-369676D01*
X209216Y-369672D01*
X209220D01*
X209305Y-370012D01*
D02*
G37*
G36*
X217956Y-377492D02*
X218019Y-377499D01*
X218082Y-377510D01*
X218137Y-377522D01*
X218189Y-377540D01*
X218241Y-377559D01*
X218285Y-377577D01*
X218326Y-377599D01*
X218363Y-377622D01*
X218396Y-377640D01*
X218422Y-377659D01*
X218448Y-377677D01*
X218467Y-377688D01*
X218478Y-377699D01*
X218485Y-377707D01*
X218489Y-377710D01*
X218530Y-377751D01*
X218567Y-377795D01*
X218596Y-377843D01*
X218622Y-377888D01*
X218648Y-377932D01*
X218667Y-377977D01*
X218692Y-378062D01*
X218704Y-378099D01*
X218711Y-378136D01*
X218715Y-378165D01*
X218718Y-378195D01*
X218722Y-378217D01*
Y-378247D01*
X218718Y-378313D01*
X218707Y-378376D01*
X218696Y-378435D01*
X218681Y-378487D01*
X218663Y-378532D01*
X218652Y-378565D01*
X218641Y-378587D01*
X218637Y-378591D01*
Y-378595D01*
X218600Y-378654D01*
X218559Y-378706D01*
X218519Y-378754D01*
X218474Y-378791D01*
X218437Y-378824D01*
X218408Y-378850D01*
X218385Y-378865D01*
X218382Y-378868D01*
X218448D01*
X218515Y-378865D01*
X218574Y-378861D01*
X218633Y-378854D01*
X218685Y-378850D01*
X218733Y-378842D01*
X218778Y-378835D01*
X218818Y-378824D01*
X218855Y-378817D01*
X218885Y-378809D01*
X218911Y-378802D01*
X218933Y-378798D01*
X218948Y-378791D01*
X218959Y-378787D01*
X218966Y-378783D01*
X218970D01*
X219044Y-378746D01*
X219111Y-378709D01*
X219162Y-378669D01*
X219207Y-378632D01*
X219244Y-378598D01*
X219270Y-378572D01*
X219285Y-378554D01*
X219288Y-378547D01*
X219318Y-378502D01*
X219336Y-378458D01*
X219351Y-378413D01*
X219362Y-378369D01*
X219370Y-378336D01*
X219373Y-378306D01*
Y-378280D01*
X219366Y-378214D01*
X219351Y-378151D01*
X219329Y-378099D01*
X219307Y-378051D01*
X219281Y-378014D01*
X219259Y-377988D01*
X219244Y-377973D01*
X219236Y-377966D01*
X219203Y-377940D01*
X219162Y-377914D01*
X219118Y-377892D01*
X219074Y-377877D01*
X219033Y-377862D01*
X219000Y-377851D01*
X218977Y-377847D01*
X218974Y-377843D01*
X218970D01*
X218996Y-377529D01*
X219099Y-377551D01*
X219192Y-377585D01*
X219273Y-377622D01*
X219340Y-377662D01*
X219392Y-377703D01*
X219414Y-377718D01*
X219432Y-377736D01*
X219444Y-377747D01*
X219455Y-377758D01*
X219458Y-377762D01*
X219462Y-377766D01*
X219492Y-377803D01*
X219517Y-377843D01*
X219562Y-377925D01*
X219592Y-378006D01*
X219610Y-378084D01*
X219625Y-378154D01*
X219629Y-378184D01*
Y-378210D01*
X219632Y-378232D01*
Y-378262D01*
X219629Y-378336D01*
X219621Y-378406D01*
X219606Y-378472D01*
X219588Y-378535D01*
X219562Y-378591D01*
X219540Y-378646D01*
X219510Y-378695D01*
X219484Y-378739D01*
X219458Y-378776D01*
X219429Y-378813D01*
X219407Y-378842D01*
X219384Y-378865D01*
X219362Y-378883D01*
X219347Y-378898D01*
X219340Y-378905D01*
X219336Y-378909D01*
X219270Y-378957D01*
X219192Y-378998D01*
X219111Y-379035D01*
X219025Y-379068D01*
X218937Y-379094D01*
X218848Y-379116D01*
X218755Y-379135D01*
X218670Y-379150D01*
X218585Y-379161D01*
X218508Y-379168D01*
X218437Y-379175D01*
X218378Y-379179D01*
X218326D01*
X218289Y-379183D01*
X218274D01*
X218263D01*
X218260D01*
X218256D01*
X218137Y-379179D01*
X218026Y-379172D01*
X217923Y-379161D01*
X217827Y-379142D01*
X217742Y-379124D01*
X217664Y-379105D01*
X217594Y-379083D01*
X217531Y-379057D01*
X217479Y-379035D01*
X217431Y-379013D01*
X217394Y-378994D01*
X217360Y-378972D01*
X217335Y-378957D01*
X217320Y-378946D01*
X217309Y-378939D01*
X217305Y-378935D01*
X217253Y-378887D01*
X217209Y-378835D01*
X217172Y-378783D01*
X217139Y-378731D01*
X217109Y-378676D01*
X217087Y-378624D01*
X217068Y-378572D01*
X217053Y-378521D01*
X217042Y-378476D01*
X217031Y-378432D01*
X217024Y-378395D01*
X217020Y-378362D01*
Y-378332D01*
X217016Y-378313D01*
Y-378295D01*
X217020Y-378210D01*
X217035Y-378132D01*
X217050Y-378062D01*
X217072Y-377999D01*
X217090Y-377951D01*
X217109Y-377914D01*
X217113Y-377899D01*
X217120Y-377888D01*
X217124Y-377884D01*
Y-377881D01*
X217168Y-377818D01*
X217220Y-377758D01*
X217272Y-377710D01*
X217323Y-377670D01*
X217372Y-377636D01*
X217409Y-377614D01*
X217423Y-377607D01*
X217435Y-377599D01*
X217438Y-377596D01*
X217442D01*
X217519Y-377559D01*
X217601Y-377533D01*
X217675Y-377514D01*
X217745Y-377503D01*
X217804Y-377492D01*
X217827D01*
X217849Y-377488D01*
X217867D01*
X217879D01*
X217886D01*
X217890D01*
X217956Y-377492D01*
D02*
G37*
G36*
X217964Y-379838D02*
X219621D01*
Y-380093D01*
X217964Y-381266D01*
X217675D01*
Y-380152D01*
X217061D01*
Y-379838D01*
X217675D01*
Y-379490D01*
X217964D01*
Y-379838D01*
D02*
G37*
G36*
X217956Y-381788D02*
X217897Y-381803D01*
X217841Y-381821D01*
X217790Y-381839D01*
X217742Y-381858D01*
X217697Y-381880D01*
X217660Y-381902D01*
X217623Y-381928D01*
X217590Y-381950D01*
X217560Y-381969D01*
X217538Y-381991D01*
X217516Y-382010D01*
X217497Y-382025D01*
X217486Y-382039D01*
X217475Y-382050D01*
X217472Y-382054D01*
X217468Y-382058D01*
X217438Y-382095D01*
X217416Y-382136D01*
X217375Y-382217D01*
X217346Y-382295D01*
X217327Y-382372D01*
X217312Y-382439D01*
X217309Y-382465D01*
Y-382491D01*
X217305Y-382513D01*
Y-382539D01*
X217309Y-382624D01*
X217323Y-382705D01*
X217342Y-382779D01*
X217364Y-382846D01*
X217386Y-382898D01*
X217397Y-382920D01*
X217405Y-382938D01*
X217412Y-382953D01*
X217420Y-382964D01*
X217423Y-382972D01*
Y-382975D01*
X217475Y-383046D01*
X217531Y-383105D01*
X217594Y-383157D01*
X217653Y-383197D01*
X217705Y-383231D01*
X217749Y-383253D01*
X217768Y-383260D01*
X217778Y-383268D01*
X217786Y-383271D01*
X217790D01*
X217886Y-383301D01*
X217982Y-383323D01*
X218078Y-383342D01*
X218167Y-383353D01*
X218208Y-383356D01*
X218245Y-383360D01*
X218278D01*
X218304Y-383364D01*
X218326D01*
X218345D01*
X218356D01*
X218359D01*
X218456Y-383360D01*
X218545Y-383353D01*
X218626Y-383338D01*
X218700Y-383323D01*
X218763Y-383312D01*
X218789Y-383305D01*
X218811Y-383297D01*
X218829Y-383294D01*
X218841Y-383290D01*
X218848Y-383286D01*
X218851D01*
X218937Y-383249D01*
X219014Y-383208D01*
X219077Y-383164D01*
X219133Y-383116D01*
X219177Y-383075D01*
X219207Y-383042D01*
X219225Y-383016D01*
X219233Y-383012D01*
Y-383009D01*
X219281Y-382931D01*
X219318Y-382846D01*
X219344Y-382765D01*
X219358Y-382687D01*
X219370Y-382616D01*
X219373Y-382587D01*
Y-382561D01*
X219377Y-382542D01*
Y-382513D01*
X219373Y-382420D01*
X219358Y-382335D01*
X219336Y-382265D01*
X219314Y-382202D01*
X219288Y-382154D01*
X219270Y-382117D01*
X219255Y-382095D01*
X219247Y-382087D01*
X219192Y-382028D01*
X219129Y-381973D01*
X219062Y-381928D01*
X218996Y-381891D01*
X218937Y-381862D01*
X218907Y-381851D01*
X218885Y-381843D01*
X218866Y-381836D01*
X218851Y-381828D01*
X218844Y-381825D01*
X218841D01*
X218918Y-381492D01*
X218985Y-381514D01*
X219044Y-381536D01*
X219099Y-381566D01*
X219155Y-381592D01*
X219203Y-381621D01*
X219247Y-381655D01*
X219292Y-381684D01*
X219329Y-381714D01*
X219358Y-381743D01*
X219388Y-381769D01*
X219414Y-381795D01*
X219432Y-381814D01*
X219451Y-381832D01*
X219462Y-381847D01*
X219466Y-381854D01*
X219469Y-381858D01*
X219503Y-381910D01*
X219536Y-381962D01*
X219562Y-382013D01*
X219584Y-382069D01*
X219618Y-382180D01*
X219640Y-382280D01*
X219651Y-382328D01*
X219654Y-382369D01*
X219658Y-382409D01*
X219662Y-382443D01*
X219666Y-382469D01*
Y-382505D01*
X219658Y-382628D01*
X219640Y-382746D01*
X219618Y-382850D01*
X219603Y-382898D01*
X219588Y-382942D01*
X219573Y-382983D01*
X219558Y-383020D01*
X219547Y-383049D01*
X219536Y-383079D01*
X219525Y-383098D01*
X219517Y-383112D01*
X219514Y-383123D01*
X219510Y-383127D01*
X219447Y-383227D01*
X219373Y-383312D01*
X219299Y-383386D01*
X219225Y-383449D01*
X219159Y-383497D01*
X219129Y-383516D01*
X219103Y-383530D01*
X219085Y-383545D01*
X219070Y-383553D01*
X219059Y-383556D01*
X219055Y-383560D01*
X218940Y-383612D01*
X218822Y-383649D01*
X218704Y-383675D01*
X218596Y-383693D01*
X218548Y-383701D01*
X218500Y-383704D01*
X218463Y-383708D01*
X218426D01*
X218400Y-383712D01*
X218378D01*
X218363D01*
X218359D01*
X218226Y-383704D01*
X218097Y-383689D01*
X217982Y-383671D01*
X217927Y-383656D01*
X217879Y-383645D01*
X217834Y-383634D01*
X217793Y-383619D01*
X217756Y-383608D01*
X217727Y-383601D01*
X217705Y-383590D01*
X217686Y-383586D01*
X217675Y-383578D01*
X217671D01*
X217560Y-383523D01*
X217460Y-383460D01*
X217375Y-383394D01*
X217342Y-383360D01*
X217309Y-383331D01*
X217279Y-383301D01*
X217253Y-383271D01*
X217231Y-383245D01*
X217216Y-383223D01*
X217201Y-383208D01*
X217190Y-383194D01*
X217186Y-383186D01*
X217183Y-383183D01*
X217153Y-383131D01*
X217127Y-383079D01*
X217087Y-382968D01*
X217057Y-382857D01*
X217038Y-382750D01*
X217031Y-382698D01*
X217024Y-382653D01*
X217020Y-382613D01*
Y-382579D01*
X217016Y-382550D01*
Y-382509D01*
X217020Y-382435D01*
X217027Y-382365D01*
X217035Y-382298D01*
X217050Y-382235D01*
X217068Y-382176D01*
X217087Y-382121D01*
X217105Y-382069D01*
X217127Y-382021D01*
X217146Y-381980D01*
X217164Y-381939D01*
X217183Y-381910D01*
X217201Y-381880D01*
X217216Y-381862D01*
X217224Y-381843D01*
X217231Y-381836D01*
X217235Y-381832D01*
X217279Y-381780D01*
X217323Y-381736D01*
X217375Y-381695D01*
X217427Y-381655D01*
X217531Y-381588D01*
X217634Y-381536D01*
X217682Y-381514D01*
X217727Y-381495D01*
X217768Y-381481D01*
X217801Y-381469D01*
X217830Y-381458D01*
X217853Y-381451D01*
X217867Y-381447D01*
X217871D01*
X217956Y-381788D01*
D02*
G37*
G36*
X222429Y-366036D02*
X222489Y-365996D01*
X222549Y-365955D01*
X222608Y-365915D01*
X222659Y-365874D01*
X222704Y-365841D01*
X222748Y-365807D01*
X222785Y-365778D01*
X222815Y-365748D01*
X222841Y-365726D01*
X222863Y-365711D01*
X222878Y-365696D01*
X222885Y-365689D01*
X222889Y-365685D01*
X223137D01*
Y-367343D01*
X222833D01*
Y-366089D01*
X222726Y-366177D01*
X222611Y-366263D01*
X222500Y-366336D01*
X222413Y-366394D01*
X222411Y-366408D01*
X222400Y-366496D01*
X222381Y-366578D01*
X222370Y-366618D01*
X222359Y-366652D01*
Y-366655D01*
X222356Y-366659D01*
X222344Y-366681D01*
X222330Y-366715D01*
X222304Y-366755D01*
X222270Y-366800D01*
X222226Y-366848D01*
X222174Y-366892D01*
X222115Y-366937D01*
X222111D01*
X222108Y-366940D01*
X222085Y-366955D01*
X222048Y-366970D01*
X222000Y-366992D01*
X221945Y-367011D01*
X221878Y-367029D01*
X221808Y-367040D01*
X221730Y-367044D01*
X221726D01*
X221719D01*
X221704D01*
X221686Y-367040D01*
X221660D01*
X221634Y-367037D01*
X221571Y-367022D01*
X221497Y-367000D01*
X221419Y-366970D01*
X221342Y-366926D01*
X221305Y-366896D01*
X221286Y-366881D01*
X221183Y-366906D01*
X221109Y-366921D01*
X221042Y-366932D01*
X220980Y-366943D01*
X220917Y-366954D01*
X220865Y-366962D01*
X220813Y-366969D01*
X220769Y-366973D01*
X220728Y-366977D01*
X220691Y-366980D01*
X220661D01*
X220639Y-366984D01*
X220624D01*
X220613D01*
X220610D01*
Y-366776D01*
X220565Y-366807D01*
X219869Y-367248D01*
Y-366826D01*
X220402Y-366489D01*
X220406D01*
X220413Y-366482D01*
X220424Y-366474D01*
X220439Y-366463D01*
X220480Y-366437D01*
X220531Y-366404D01*
X220587Y-366363D01*
X220646Y-366322D01*
X220702Y-366282D01*
X220753Y-366245D01*
X220757Y-366241D01*
X220772Y-366230D01*
X220794Y-366212D01*
X220820Y-366186D01*
X220876Y-366130D01*
X220901Y-366101D01*
X220923Y-366071D01*
X220927Y-366067D01*
X220931Y-366060D01*
X220938Y-366045D01*
X220949Y-366023D01*
X220961Y-366001D01*
X220972Y-365975D01*
X220990Y-365915D01*
Y-365912D01*
X220994Y-365904D01*
Y-365890D01*
X220998Y-365871D01*
X221001Y-365845D01*
Y-365816D01*
X221005Y-365775D01*
Y-365338D01*
X219869D01*
Y-364998D01*
X222429D01*
Y-366036D01*
D02*
G37*
G36*
X219939Y-367407D02*
X219973Y-367410D01*
X220010Y-367418D01*
X220047Y-367425D01*
X220087Y-367440D01*
X220091D01*
X220095Y-367444D01*
X220117Y-367451D01*
X220150Y-367466D01*
X220195Y-367488D01*
X220247Y-367518D01*
X220306Y-367555D01*
X220365Y-367595D01*
X220428Y-367647D01*
X220431D01*
X220435Y-367654D01*
X220457Y-367673D01*
X220491Y-367706D01*
X220539Y-367754D01*
X220594Y-367810D01*
X220661Y-367880D01*
X220735Y-367965D01*
X220793Y-368035D01*
X221224D01*
Y-367687D01*
X221512D01*
Y-368035D01*
X222122D01*
X222089Y-367976D01*
X222045Y-367921D01*
X222037Y-367914D01*
X222019Y-367899D01*
X221989Y-367877D01*
X221945Y-367854D01*
X221893Y-367828D01*
X221826Y-367806D01*
X221752Y-367791D01*
X221667Y-367784D01*
X221701Y-367462D01*
X221704D01*
X221715Y-367466D01*
X221734D01*
X221760Y-367470D01*
X221789Y-367477D01*
X221823Y-367484D01*
X221863Y-367495D01*
X221904Y-367507D01*
X221993Y-367536D01*
X222082Y-367581D01*
X222126Y-367606D01*
X222170Y-367640D01*
X222211Y-367673D01*
X222248Y-367710D01*
X222252Y-367714D01*
X222255Y-367721D01*
X222267Y-367732D01*
X222278Y-367751D01*
X222292Y-367773D01*
X222307Y-367799D01*
X222326Y-367828D01*
X222344Y-367865D01*
X222363Y-367906D01*
X222381Y-367951D01*
X222396Y-367999D01*
X222407Y-368035D01*
X223170D01*
Y-368290D01*
X221512Y-369463D01*
X221224D01*
Y-368911D01*
X221175Y-368872D01*
X221112Y-368820D01*
X221105Y-368813D01*
X221083Y-368794D01*
X221064Y-368776D01*
X221046Y-368757D01*
X221024Y-368735D01*
X220994Y-368705D01*
X220964Y-368676D01*
X220931Y-368639D01*
X220894Y-368602D01*
X220853Y-368557D01*
X220813Y-368509D01*
X220764Y-368457D01*
X220716Y-368398D01*
X220674Y-368349D01*
X220610D01*
Y-368277D01*
X220605Y-368272D01*
X220583Y-368247D01*
X220535Y-368187D01*
X220480Y-368124D01*
X220424Y-368065D01*
X220376Y-368013D01*
X220357Y-367991D01*
X220339Y-367973D01*
X220335Y-367969D01*
X220324Y-367958D01*
X220309Y-367943D01*
X220287Y-367925D01*
X220261Y-367906D01*
X220235Y-367884D01*
X220172Y-367840D01*
Y-369101D01*
X219869D01*
Y-367403D01*
X219873D01*
X219888D01*
X219910D01*
X219939Y-367407D01*
D02*
G37*
G36*
X220587Y-369756D02*
X220583D01*
X220576Y-369760D01*
X220561Y-369763D01*
X220543Y-369767D01*
X220520Y-369771D01*
X220494Y-369778D01*
X220439Y-369797D01*
X220372Y-369823D01*
X220309Y-369856D01*
X220250Y-369893D01*
X220198Y-369937D01*
X220195Y-369945D01*
X220180Y-369960D01*
X220161Y-369989D01*
X220143Y-370026D01*
X220121Y-370071D01*
X220102Y-370126D01*
X220087Y-370189D01*
X220084Y-370256D01*
Y-370278D01*
X220087Y-370293D01*
X220091Y-370333D01*
X220102Y-370385D01*
X220121Y-370444D01*
X220146Y-370507D01*
X220184Y-370570D01*
X220235Y-370629D01*
X220243Y-370637D01*
X220265Y-370655D01*
X220298Y-370677D01*
X220343Y-370707D01*
X220398Y-370737D01*
X220461Y-370759D01*
X220535Y-370777D01*
X220569Y-370780D01*
Y-370777D01*
X220565Y-370747D01*
Y-370706D01*
X220569Y-370632D01*
X220576Y-370562D01*
X220584Y-370495D01*
X220599Y-370432D01*
X220617Y-370373D01*
X220636Y-370318D01*
X220654Y-370266D01*
X220676Y-370218D01*
X220695Y-370177D01*
X220713Y-370136D01*
X220732Y-370107D01*
X220750Y-370077D01*
X220765Y-370059D01*
X220772Y-370040D01*
X220780Y-370033D01*
X220784Y-370029D01*
X220828Y-369977D01*
X220872Y-369933D01*
X220924Y-369892D01*
X220976Y-369851D01*
X221080Y-369785D01*
X221183Y-369733D01*
X221231Y-369711D01*
X221276Y-369692D01*
X221316Y-369678D01*
X221350Y-369667D01*
X221379Y-369655D01*
X221402Y-369648D01*
X221416Y-369644D01*
X221420D01*
X221505Y-369985D01*
X221446Y-370000D01*
X221390Y-370018D01*
X221339Y-370037D01*
X221290Y-370055D01*
X221246Y-370077D01*
X221240Y-370080D01*
X221360Y-370096D01*
Y-370115D01*
X221356Y-370130D01*
Y-370178D01*
X221364Y-370219D01*
X221371Y-370267D01*
X221382Y-370322D01*
X221401Y-370385D01*
X221427Y-370444D01*
X221460Y-370507D01*
Y-370511D01*
X221464Y-370515D01*
X221479Y-370533D01*
X221504Y-370559D01*
X221538Y-370589D01*
X221586Y-370618D01*
X221641Y-370644D01*
X221704Y-370663D01*
X221741Y-370670D01*
X221782D01*
X221786D01*
X221789D01*
X221812D01*
X221841Y-370663D01*
X221882Y-370655D01*
X221926Y-370640D01*
X221974Y-370622D01*
X222022Y-370592D01*
X222067Y-370552D01*
X222071Y-370548D01*
X222085Y-370529D01*
X222104Y-370503D01*
X222126Y-370470D01*
X222145Y-370426D01*
X222163Y-370374D01*
X222178Y-370315D01*
X222182Y-370248D01*
Y-370219D01*
X222174Y-370185D01*
X222167Y-370141D01*
X222152Y-370093D01*
X222133Y-370045D01*
X222104Y-369993D01*
X222067Y-369945D01*
X222063Y-369941D01*
X222045Y-369926D01*
X222019Y-369904D01*
X221982Y-369878D01*
X221934Y-369852D01*
X221874Y-369826D01*
X221804Y-369804D01*
X221723Y-369789D01*
X221778Y-369475D01*
X221782D01*
X221793Y-369479D01*
X221808Y-369482D01*
X221830Y-369486D01*
X221856Y-369493D01*
X221886Y-369504D01*
X221956Y-369527D01*
X222037Y-369564D01*
X222119Y-369608D01*
X222196Y-369664D01*
X222267Y-369734D01*
X222270Y-369738D01*
X222274Y-369745D01*
X222281Y-369756D01*
X222292Y-369771D01*
X222307Y-369789D01*
X222322Y-369815D01*
X222337Y-369841D01*
X222356Y-369875D01*
X222385Y-369949D01*
X222398Y-369985D01*
X222467Y-369689D01*
X222534Y-369711D01*
X222593Y-369733D01*
X222648Y-369763D01*
X222704Y-369789D01*
X222752Y-369818D01*
X222796Y-369851D01*
X222841Y-369881D01*
X222878Y-369911D01*
X222907Y-369940D01*
X222937Y-369966D01*
X222963Y-369992D01*
X222981Y-370011D01*
X223000Y-370029D01*
X223011Y-370044D01*
X223015Y-370051D01*
X223018Y-370055D01*
X223052Y-370107D01*
X223085Y-370159D01*
X223111Y-370210D01*
X223133Y-370266D01*
X223166Y-370377D01*
X223188Y-370477D01*
X223200Y-370525D01*
X223203Y-370566D01*
X223207Y-370606D01*
X223211Y-370640D01*
X223214Y-370666D01*
Y-370703D01*
X223207Y-370825D01*
X223188Y-370943D01*
X223166Y-371047D01*
X223151Y-371095D01*
X223137Y-371139D01*
X223122Y-371180D01*
X223107Y-371217D01*
X223096Y-371246D01*
X223085Y-371276D01*
X223074Y-371294D01*
X223066Y-371309D01*
X223063Y-371320D01*
X223059Y-371324D01*
X222996Y-371424D01*
X222922Y-371509D01*
X222848Y-371583D01*
X222774Y-371646D01*
X222708Y-371694D01*
X222678Y-371713D01*
X222652Y-371727D01*
X222634Y-371742D01*
X222619Y-371750D01*
X222608Y-371753D01*
X222604Y-371757D01*
X222489Y-371809D01*
X222371Y-371846D01*
X222252Y-371872D01*
X222145Y-371890D01*
X222097Y-371898D01*
X222049Y-371901D01*
X222012Y-371905D01*
X221975D01*
X221949Y-371909D01*
X221927D01*
X221912D01*
X221908D01*
X221775Y-371901D01*
X221646Y-371886D01*
X221531Y-371868D01*
X221476Y-371853D01*
X221427Y-371842D01*
X221383Y-371831D01*
X221342Y-371816D01*
X221305Y-371805D01*
X221276Y-371798D01*
X221253Y-371787D01*
X221235Y-371783D01*
X221224Y-371776D01*
X221220D01*
X221109Y-371720D01*
X221009Y-371657D01*
X220924Y-371590D01*
X220891Y-371557D01*
X220858Y-371528D01*
X220828Y-371498D01*
X220802Y-371468D01*
X220780Y-371443D01*
X220765Y-371420D01*
X220750Y-371406D01*
X220739Y-371391D01*
X220735Y-371383D01*
X220732Y-371380D01*
X220702Y-371328D01*
X220676Y-371276D01*
X220636Y-371165D01*
X220623Y-371118D01*
X220620D01*
X220609D01*
X220590D01*
X220568Y-371114D01*
X220539Y-371110D01*
X220505Y-371103D01*
X220468Y-371095D01*
X220428Y-371088D01*
X220339Y-371059D01*
X220291Y-371036D01*
X220247Y-371014D01*
X220198Y-370985D01*
X220150Y-370951D01*
X220102Y-370914D01*
X220058Y-370870D01*
X220054Y-370866D01*
X220047Y-370859D01*
X220036Y-370844D01*
X220021Y-370825D01*
X220002Y-370803D01*
X219984Y-370774D01*
X219962Y-370740D01*
X219943Y-370700D01*
X219921Y-370659D01*
X219899Y-370611D01*
X219880Y-370563D01*
X219862Y-370507D01*
X219847Y-370448D01*
X219836Y-370385D01*
X219828Y-370322D01*
X219825Y-370252D01*
Y-370219D01*
X219828Y-370196D01*
X219832Y-370167D01*
X219836Y-370133D01*
X219843Y-370096D01*
X219851Y-370056D01*
X219873Y-369967D01*
X219910Y-369875D01*
X219932Y-369826D01*
X219958Y-369782D01*
X219991Y-369738D01*
X220024Y-369693D01*
X220028Y-369689D01*
X220036Y-369682D01*
X220047Y-369671D01*
X220061Y-369660D01*
X220080Y-369641D01*
X220106Y-369623D01*
X220132Y-369601D01*
X220165Y-369579D01*
X220202Y-369556D01*
X220239Y-369534D01*
X220328Y-369493D01*
X220431Y-369460D01*
X220487Y-369449D01*
X220546Y-369442D01*
X220587Y-369756D01*
D02*
G37*
G36*
X236724Y-365691D02*
X236801Y-365706D01*
X236872Y-365728D01*
X236931Y-365750D01*
X236979Y-365772D01*
X237016Y-365794D01*
X237038Y-365809D01*
X237042Y-365813D01*
X237046D01*
X237105Y-365865D01*
X237157Y-365920D01*
X237197Y-365980D01*
X237234Y-366035D01*
X237260Y-366087D01*
X237279Y-366131D01*
X237286Y-366146D01*
X237290Y-366157D01*
X237293Y-366164D01*
Y-366168D01*
X237323Y-366102D01*
X237356Y-366046D01*
X237390Y-365998D01*
X237423Y-365957D01*
X237453Y-365928D01*
X237475Y-365905D01*
X237490Y-365891D01*
X237497Y-365887D01*
X237549Y-365854D01*
X237600Y-365831D01*
X237652Y-365813D01*
X237704Y-365802D01*
X237745Y-365794D01*
X237778Y-365791D01*
X237800D01*
X237804D01*
X237808D01*
X237860Y-365794D01*
X237908Y-365798D01*
X238000Y-365824D01*
X238082Y-365857D01*
X238152Y-365894D01*
X238207Y-365931D01*
X238229Y-365950D01*
X238252Y-365965D01*
X238266Y-365980D01*
X238278Y-365991D01*
X238281Y-365994D01*
X238285Y-365998D01*
X238318Y-366039D01*
X238352Y-366079D01*
X238377Y-366124D01*
X238400Y-366168D01*
X238433Y-366257D01*
X238455Y-366346D01*
X238466Y-366383D01*
X238470Y-366420D01*
X238474Y-366453D01*
X238477Y-366483D01*
X238481Y-366505D01*
Y-366538D01*
X238477Y-366597D01*
X238474Y-366657D01*
X238452Y-366760D01*
X238437Y-366808D01*
X238422Y-366853D01*
X238403Y-366893D01*
X238385Y-366930D01*
X238366Y-366960D01*
X238348Y-366990D01*
X238333Y-367016D01*
X238318Y-367034D01*
X238307Y-367049D01*
X238296Y-367060D01*
X238292Y-367067D01*
X238289Y-367071D01*
X238252Y-367104D01*
X238215Y-367138D01*
X238174Y-367163D01*
X238133Y-367186D01*
X238056Y-367223D01*
X237982Y-367245D01*
X237919Y-367260D01*
X237889Y-367263D01*
X237867Y-367267D01*
X237845Y-367271D01*
X237830D01*
X237823D01*
X237819D01*
X237752Y-367267D01*
X237689Y-367256D01*
X237634Y-367241D01*
X237586Y-367223D01*
X237549Y-367208D01*
X237519Y-367193D01*
X237504Y-367182D01*
X237497Y-367178D01*
X237453Y-367138D01*
X237412Y-367093D01*
X237375Y-367045D01*
X237345Y-366997D01*
X237323Y-366953D01*
X237308Y-366919D01*
X237301Y-366904D01*
X237297Y-366893D01*
X237293Y-366890D01*
Y-366886D01*
X237267Y-366971D01*
X237234Y-367041D01*
X237193Y-367104D01*
X237157Y-367156D01*
X237120Y-367197D01*
X237090Y-367226D01*
X237071Y-367241D01*
X237068Y-367249D01*
X237064D01*
X236997Y-367289D01*
X236927Y-367323D01*
X236860Y-367345D01*
X236794Y-367360D01*
X236735Y-367367D01*
X236709Y-367371D01*
X236687D01*
X236672Y-367374D01*
X236657D01*
X236650D01*
X236646D01*
X236587Y-367371D01*
X236527Y-367363D01*
X236472Y-367352D01*
X236417Y-367337D01*
X236324Y-367300D01*
X236280Y-367282D01*
X236243Y-367260D01*
X236206Y-367237D01*
X236176Y-367219D01*
X236150Y-367197D01*
X236128Y-367182D01*
X236109Y-367167D01*
X236098Y-367156D01*
X236091Y-367149D01*
X236087Y-367145D01*
X236047Y-367101D01*
X236013Y-367053D01*
X235984Y-367001D01*
X235958Y-366949D01*
X235939Y-366901D01*
X235921Y-366849D01*
X235895Y-366749D01*
X235884Y-366705D01*
X235876Y-366664D01*
X235873Y-366627D01*
X235869Y-366594D01*
X235865Y-366568D01*
Y-366531D01*
X235869Y-366460D01*
X235876Y-366398D01*
X235887Y-366335D01*
X235898Y-366276D01*
X235917Y-366224D01*
X235935Y-366172D01*
X235954Y-366124D01*
X235976Y-366083D01*
X235998Y-366046D01*
X236017Y-366013D01*
X236035Y-365987D01*
X236054Y-365961D01*
X236065Y-365943D01*
X236076Y-365931D01*
X236084Y-365924D01*
X236087Y-365920D01*
X236132Y-365880D01*
X236176Y-365843D01*
X236220Y-365813D01*
X236268Y-365787D01*
X236313Y-365761D01*
X236361Y-365743D01*
X236446Y-365717D01*
X236487Y-365706D01*
X236524Y-365698D01*
X236557Y-365695D01*
X236583Y-365691D01*
X236605Y-365687D01*
X236624D01*
X236635D01*
X236638D01*
X236724Y-365691D01*
D02*
G37*
G36*
X236812Y-368040D02*
X238470D01*
Y-368296D01*
X236812Y-369469D01*
X236524D01*
Y-368355D01*
X235910D01*
Y-368040D01*
X236524D01*
Y-367693D01*
X236812D01*
Y-368040D01*
D02*
G37*
G36*
X236805Y-369990D02*
X236746Y-370005D01*
X236690Y-370024D01*
X236638Y-370042D01*
X236590Y-370061D01*
X236546Y-370083D01*
X236509Y-370105D01*
X236472Y-370131D01*
X236439Y-370153D01*
X236409Y-370172D01*
X236387Y-370194D01*
X236365Y-370212D01*
X236346Y-370227D01*
X236335Y-370242D01*
X236324Y-370253D01*
X236320Y-370257D01*
X236317Y-370260D01*
X236287Y-370297D01*
X236265Y-370338D01*
X236224Y-370420D01*
X236194Y-370497D01*
X236176Y-370575D01*
X236161Y-370641D01*
X236157Y-370667D01*
Y-370693D01*
X236154Y-370715D01*
Y-370741D01*
X236157Y-370827D01*
X236172Y-370908D01*
X236191Y-370982D01*
X236213Y-371048D01*
X236235Y-371100D01*
X236246Y-371123D01*
X236254Y-371141D01*
X236261Y-371156D01*
X236268Y-371167D01*
X236272Y-371174D01*
Y-371178D01*
X236324Y-371248D01*
X236380Y-371307D01*
X236442Y-371359D01*
X236502Y-371400D01*
X236553Y-371433D01*
X236598Y-371456D01*
X236616Y-371463D01*
X236627Y-371470D01*
X236635Y-371474D01*
X236638D01*
X236735Y-371504D01*
X236831Y-371526D01*
X236927Y-371544D01*
X237016Y-371555D01*
X237057Y-371559D01*
X237094Y-371563D01*
X237127D01*
X237153Y-371567D01*
X237175D01*
X237193D01*
X237205D01*
X237208D01*
X237304Y-371563D01*
X237393Y-371555D01*
X237475Y-371541D01*
X237549Y-371526D01*
X237612Y-371515D01*
X237637Y-371507D01*
X237660Y-371500D01*
X237678Y-371496D01*
X237689Y-371493D01*
X237697Y-371489D01*
X237700D01*
X237786Y-371452D01*
X237863Y-371411D01*
X237926Y-371367D01*
X237982Y-371319D01*
X238026Y-371278D01*
X238056Y-371245D01*
X238074Y-371219D01*
X238082Y-371215D01*
Y-371211D01*
X238130Y-371134D01*
X238167Y-371048D01*
X238193Y-370967D01*
X238207Y-370889D01*
X238218Y-370819D01*
X238222Y-370790D01*
Y-370764D01*
X238226Y-370745D01*
Y-370715D01*
X238222Y-370623D01*
X238207Y-370538D01*
X238185Y-370468D01*
X238163Y-370405D01*
X238137Y-370357D01*
X238119Y-370320D01*
X238104Y-370297D01*
X238096Y-370290D01*
X238041Y-370231D01*
X237978Y-370175D01*
X237911Y-370131D01*
X237845Y-370094D01*
X237786Y-370064D01*
X237756Y-370053D01*
X237734Y-370046D01*
X237715Y-370038D01*
X237700Y-370031D01*
X237693Y-370027D01*
X237689D01*
X237767Y-369694D01*
X237834Y-369717D01*
X237893Y-369739D01*
X237948Y-369768D01*
X238004Y-369794D01*
X238052Y-369824D01*
X238096Y-369857D01*
X238141Y-369887D01*
X238178Y-369916D01*
X238207Y-369946D01*
X238237Y-369972D01*
X238263Y-369998D01*
X238281Y-370016D01*
X238300Y-370035D01*
X238311Y-370050D01*
X238315Y-370057D01*
X238318Y-370061D01*
X238352Y-370112D01*
X238385Y-370164D01*
X238411Y-370216D01*
X238433Y-370271D01*
X238466Y-370382D01*
X238489Y-370482D01*
X238500Y-370531D01*
X238503Y-370571D01*
X238507Y-370612D01*
X238511Y-370645D01*
X238514Y-370671D01*
Y-370708D01*
X238507Y-370830D01*
X238489Y-370949D01*
X238466Y-371052D01*
X238452Y-371100D01*
X238437Y-371145D01*
X238422Y-371185D01*
X238407Y-371222D01*
X238396Y-371252D01*
X238385Y-371282D01*
X238374Y-371300D01*
X238366Y-371315D01*
X238363Y-371326D01*
X238359Y-371330D01*
X238296Y-371430D01*
X238222Y-371515D01*
X238148Y-371589D01*
X238074Y-371652D01*
X238007Y-371700D01*
X237978Y-371718D01*
X237952Y-371733D01*
X237933Y-371748D01*
X237919Y-371755D01*
X237908Y-371759D01*
X237904Y-371763D01*
X237789Y-371814D01*
X237671Y-371851D01*
X237552Y-371877D01*
X237445Y-371896D01*
X237397Y-371903D01*
X237349Y-371907D01*
X237312Y-371911D01*
X237275D01*
X237249Y-371914D01*
X237227D01*
X237212D01*
X237208D01*
X237075Y-371907D01*
X236946Y-371892D01*
X236831Y-371874D01*
X236775Y-371859D01*
X236727Y-371848D01*
X236683Y-371837D01*
X236642Y-371822D01*
X236605Y-371811D01*
X236576Y-371803D01*
X236553Y-371792D01*
X236535Y-371789D01*
X236524Y-371781D01*
X236520D01*
X236409Y-371726D01*
X236309Y-371663D01*
X236224Y-371596D01*
X236191Y-371563D01*
X236157Y-371533D01*
X236128Y-371504D01*
X236102Y-371474D01*
X236080Y-371448D01*
X236065Y-371426D01*
X236050Y-371411D01*
X236039Y-371396D01*
X236035Y-371389D01*
X236032Y-371385D01*
X236002Y-371333D01*
X235976Y-371282D01*
X235935Y-371171D01*
X235906Y-371060D01*
X235887Y-370952D01*
X235880Y-370901D01*
X235873Y-370856D01*
X235869Y-370815D01*
Y-370782D01*
X235865Y-370753D01*
Y-370712D01*
X235869Y-370638D01*
X235876Y-370567D01*
X235884Y-370501D01*
X235898Y-370438D01*
X235917Y-370379D01*
X235935Y-370323D01*
X235954Y-370271D01*
X235976Y-370223D01*
X235995Y-370183D01*
X236013Y-370142D01*
X236032Y-370112D01*
X236050Y-370083D01*
X236065Y-370064D01*
X236072Y-370046D01*
X236080Y-370038D01*
X236084Y-370035D01*
X236128Y-369983D01*
X236172Y-369938D01*
X236224Y-369898D01*
X236276Y-369857D01*
X236380Y-369791D01*
X236483Y-369739D01*
X236531Y-369717D01*
X236576Y-369698D01*
X236616Y-369683D01*
X236650Y-369672D01*
X236679Y-369661D01*
X236701Y-369654D01*
X236716Y-369650D01*
X236720D01*
X236805Y-369990D01*
D02*
G37*
G36*
X241408Y-365691D02*
X241482Y-365698D01*
X241552Y-365706D01*
X241615Y-365713D01*
X241674Y-365721D01*
X241730Y-365732D01*
X241778Y-365743D01*
X241819Y-365754D01*
X241856Y-365761D01*
X241889Y-365772D01*
X241915Y-365780D01*
X241933Y-365787D01*
X241948Y-365794D01*
X241956Y-365798D01*
X241959D01*
X242048Y-365843D01*
X242126Y-365891D01*
X242193Y-365946D01*
X242248Y-365994D01*
X242289Y-366042D01*
X242318Y-366079D01*
X242329Y-366094D01*
X242337Y-366105D01*
X242344Y-366109D01*
Y-366113D01*
X242389Y-366190D01*
X242422Y-366268D01*
X242448Y-366346D01*
X242463Y-366416D01*
X242474Y-366479D01*
X242477Y-366505D01*
Y-366523D01*
X242481Y-366542D01*
Y-366568D01*
X242477Y-366631D01*
X242470Y-366690D01*
X242459Y-366749D01*
X242444Y-366801D01*
X242403Y-366901D01*
X242385Y-366945D01*
X242363Y-366982D01*
X242337Y-367019D01*
X242318Y-367049D01*
X242296Y-367078D01*
X242278Y-367101D01*
X242263Y-367119D01*
X242252Y-367130D01*
X242244Y-367138D01*
X242241Y-367141D01*
X242196Y-367182D01*
X242144Y-367215D01*
X242096Y-367249D01*
X242044Y-367274D01*
X241989Y-367297D01*
X241937Y-367315D01*
X241841Y-367341D01*
X241793Y-367352D01*
X241752Y-367360D01*
X241711Y-367363D01*
X241678Y-367367D01*
X241652Y-367371D01*
X241634D01*
X241619D01*
X241615D01*
X241545Y-367367D01*
X241482Y-367360D01*
X241419Y-367352D01*
X241360Y-367337D01*
X241308Y-367319D01*
X241256Y-367300D01*
X241212Y-367282D01*
X241171Y-367260D01*
X241134Y-367241D01*
X241101Y-367223D01*
X241075Y-367204D01*
X241049Y-367186D01*
X241031Y-367171D01*
X241020Y-367163D01*
X241012Y-367156D01*
X241008Y-367152D01*
X240968Y-367112D01*
X240934Y-367067D01*
X240901Y-367023D01*
X240875Y-366975D01*
X240853Y-366930D01*
X240835Y-366886D01*
X240809Y-366801D01*
X240798Y-366764D01*
X240790Y-366727D01*
X240787Y-366697D01*
X240783Y-366668D01*
X240779Y-366646D01*
Y-366616D01*
X240783Y-366546D01*
X240794Y-366479D01*
X240809Y-366420D01*
X240827Y-366364D01*
X240842Y-366324D01*
X240857Y-366290D01*
X240868Y-366268D01*
X240872Y-366261D01*
X240909Y-366201D01*
X240949Y-366150D01*
X240990Y-366105D01*
X241027Y-366068D01*
X241064Y-366042D01*
X241090Y-366020D01*
X241108Y-366005D01*
X241116Y-366002D01*
X241086D01*
X241068D01*
X241057D01*
X241053D01*
X240979Y-366005D01*
X240909Y-366009D01*
X240846Y-366017D01*
X240787Y-366024D01*
X240738Y-366035D01*
X240701Y-366042D01*
X240687Y-366046D01*
X240675D01*
X240672Y-366050D01*
X240668D01*
X240601Y-366068D01*
X240542Y-366087D01*
X240491Y-366105D01*
X240446Y-366124D01*
X240413Y-366139D01*
X240387Y-366153D01*
X240368Y-366161D01*
X240365Y-366164D01*
X240324Y-366194D01*
X240291Y-366224D01*
X240261Y-366253D01*
X240235Y-366283D01*
X240213Y-366305D01*
X240198Y-366327D01*
X240191Y-366342D01*
X240187Y-366346D01*
X240165Y-366387D01*
X240150Y-366431D01*
X240139Y-366472D01*
X240132Y-366512D01*
X240128Y-366546D01*
X240124Y-366571D01*
Y-366597D01*
X240128Y-366657D01*
X240139Y-366712D01*
X240154Y-366760D01*
X240172Y-366801D01*
X240187Y-366830D01*
X240202Y-366856D01*
X240213Y-366871D01*
X240217Y-366875D01*
X240257Y-366912D01*
X240305Y-366941D01*
X240357Y-366967D01*
X240409Y-366986D01*
X240454Y-367001D01*
X240494Y-367012D01*
X240509Y-367016D01*
X240516D01*
X240524Y-367019D01*
X240528D01*
X240502Y-367323D01*
X240394Y-367300D01*
X240302Y-367271D01*
X240220Y-367234D01*
X240154Y-367197D01*
X240102Y-367160D01*
X240080Y-367141D01*
X240061Y-367126D01*
X240050Y-367115D01*
X240039Y-367104D01*
X240035Y-367101D01*
X240032Y-367097D01*
X240002Y-367060D01*
X239976Y-367019D01*
X239935Y-366938D01*
X239906Y-366856D01*
X239887Y-366779D01*
X239873Y-366708D01*
X239869Y-366679D01*
Y-366653D01*
X239865Y-366634D01*
Y-366605D01*
X239873Y-366501D01*
X239887Y-366409D01*
X239913Y-366324D01*
X239943Y-366253D01*
X239954Y-366224D01*
X239969Y-366194D01*
X239984Y-366172D01*
X239995Y-366150D01*
X240002Y-366135D01*
X240009Y-366124D01*
X240017Y-366116D01*
Y-366113D01*
X240080Y-366039D01*
X240150Y-365972D01*
X240224Y-365920D01*
X240294Y-365876D01*
X240357Y-365839D01*
X240387Y-365824D01*
X240409Y-365813D01*
X240431Y-365806D01*
X240446Y-365798D01*
X240454Y-365794D01*
X240457D01*
X240513Y-365776D01*
X240576Y-365757D01*
X240701Y-365732D01*
X240835Y-365713D01*
X240960Y-365702D01*
X241016Y-365695D01*
X241071Y-365691D01*
X241120D01*
X241160Y-365687D01*
X241194D01*
X241219D01*
X241238D01*
X241242D01*
X241327D01*
X241408Y-365691D01*
D02*
G37*
G36*
X240812Y-368040D02*
X242470D01*
Y-368296D01*
X240812Y-369469D01*
X240524D01*
Y-368355D01*
X239910D01*
Y-368040D01*
X240524D01*
Y-367693D01*
X240812D01*
Y-368040D01*
D02*
G37*
G36*
X240805Y-369990D02*
X240746Y-370005D01*
X240690Y-370024D01*
X240638Y-370042D01*
X240590Y-370061D01*
X240546Y-370083D01*
X240509Y-370105D01*
X240472Y-370131D01*
X240439Y-370153D01*
X240409Y-370172D01*
X240387Y-370194D01*
X240365Y-370212D01*
X240346Y-370227D01*
X240335Y-370242D01*
X240324Y-370253D01*
X240320Y-370257D01*
X240317Y-370260D01*
X240287Y-370297D01*
X240265Y-370338D01*
X240224Y-370420D01*
X240195Y-370497D01*
X240176Y-370575D01*
X240161Y-370641D01*
X240158Y-370667D01*
Y-370693D01*
X240154Y-370715D01*
Y-370741D01*
X240158Y-370827D01*
X240172Y-370908D01*
X240191Y-370982D01*
X240213Y-371048D01*
X240235Y-371100D01*
X240246Y-371123D01*
X240254Y-371141D01*
X240261Y-371156D01*
X240268Y-371167D01*
X240272Y-371174D01*
Y-371178D01*
X240324Y-371248D01*
X240380Y-371307D01*
X240442Y-371359D01*
X240502Y-371400D01*
X240553Y-371433D01*
X240598Y-371456D01*
X240616Y-371463D01*
X240627Y-371470D01*
X240635Y-371474D01*
X240638D01*
X240735Y-371504D01*
X240831Y-371526D01*
X240927Y-371544D01*
X241016Y-371555D01*
X241057Y-371559D01*
X241094Y-371563D01*
X241127D01*
X241153Y-371567D01*
X241175D01*
X241194D01*
X241205D01*
X241208D01*
X241304Y-371563D01*
X241393Y-371555D01*
X241475Y-371541D01*
X241549Y-371526D01*
X241612Y-371515D01*
X241637Y-371507D01*
X241660Y-371500D01*
X241678Y-371496D01*
X241689Y-371493D01*
X241697Y-371489D01*
X241700D01*
X241786Y-371452D01*
X241863Y-371411D01*
X241926Y-371367D01*
X241982Y-371319D01*
X242026Y-371278D01*
X242056Y-371245D01*
X242074Y-371219D01*
X242081Y-371215D01*
Y-371211D01*
X242130Y-371134D01*
X242167Y-371048D01*
X242193Y-370967D01*
X242207Y-370889D01*
X242218Y-370819D01*
X242222Y-370790D01*
Y-370764D01*
X242226Y-370745D01*
Y-370715D01*
X242222Y-370623D01*
X242207Y-370538D01*
X242185Y-370468D01*
X242163Y-370405D01*
X242137Y-370357D01*
X242119Y-370320D01*
X242104Y-370297D01*
X242096Y-370290D01*
X242041Y-370231D01*
X241978Y-370175D01*
X241911Y-370131D01*
X241845Y-370094D01*
X241786Y-370064D01*
X241756Y-370053D01*
X241734Y-370046D01*
X241715Y-370038D01*
X241700Y-370031D01*
X241693Y-370027D01*
X241689D01*
X241767Y-369694D01*
X241834Y-369717D01*
X241893Y-369739D01*
X241948Y-369768D01*
X242004Y-369794D01*
X242052Y-369824D01*
X242096Y-369857D01*
X242141Y-369887D01*
X242178Y-369916D01*
X242207Y-369946D01*
X242237Y-369972D01*
X242263Y-369998D01*
X242281Y-370016D01*
X242300Y-370035D01*
X242311Y-370050D01*
X242315Y-370057D01*
X242318Y-370061D01*
X242352Y-370112D01*
X242385Y-370164D01*
X242411Y-370216D01*
X242433Y-370271D01*
X242466Y-370382D01*
X242489Y-370482D01*
X242500Y-370531D01*
X242503Y-370571D01*
X242507Y-370612D01*
X242511Y-370645D01*
X242514Y-370671D01*
Y-370708D01*
X242507Y-370830D01*
X242489Y-370949D01*
X242466Y-371052D01*
X242452Y-371100D01*
X242437Y-371145D01*
X242422Y-371185D01*
X242407Y-371222D01*
X242396Y-371252D01*
X242385Y-371282D01*
X242374Y-371300D01*
X242366Y-371315D01*
X242363Y-371326D01*
X242359Y-371330D01*
X242296Y-371430D01*
X242222Y-371515D01*
X242148Y-371589D01*
X242074Y-371652D01*
X242007Y-371700D01*
X241978Y-371718D01*
X241952Y-371733D01*
X241933Y-371748D01*
X241919Y-371755D01*
X241908Y-371759D01*
X241904Y-371763D01*
X241789Y-371814D01*
X241671Y-371851D01*
X241552Y-371877D01*
X241445Y-371896D01*
X241397Y-371903D01*
X241349Y-371907D01*
X241312Y-371911D01*
X241275D01*
X241249Y-371914D01*
X241227D01*
X241212D01*
X241208D01*
X241075Y-371907D01*
X240946Y-371892D01*
X240831Y-371874D01*
X240775Y-371859D01*
X240727Y-371848D01*
X240683Y-371837D01*
X240642Y-371822D01*
X240605Y-371811D01*
X240576Y-371803D01*
X240553Y-371792D01*
X240535Y-371789D01*
X240524Y-371781D01*
X240520D01*
X240409Y-371726D01*
X240309Y-371663D01*
X240224Y-371596D01*
X240191Y-371563D01*
X240158Y-371533D01*
X240128Y-371504D01*
X240102Y-371474D01*
X240080Y-371448D01*
X240065Y-371426D01*
X240050Y-371411D01*
X240039Y-371396D01*
X240035Y-371389D01*
X240032Y-371385D01*
X240002Y-371333D01*
X239976Y-371282D01*
X239935Y-371171D01*
X239906Y-371060D01*
X239887Y-370952D01*
X239880Y-370901D01*
X239873Y-370856D01*
X239869Y-370815D01*
Y-370782D01*
X239865Y-370753D01*
Y-370712D01*
X239869Y-370638D01*
X239876Y-370567D01*
X239884Y-370501D01*
X239898Y-370438D01*
X239917Y-370379D01*
X239935Y-370323D01*
X239954Y-370271D01*
X239976Y-370223D01*
X239995Y-370183D01*
X240013Y-370142D01*
X240032Y-370112D01*
X240050Y-370083D01*
X240065Y-370064D01*
X240072Y-370046D01*
X240080Y-370038D01*
X240084Y-370035D01*
X240128Y-369983D01*
X240172Y-369938D01*
X240224Y-369898D01*
X240276Y-369857D01*
X240380Y-369791D01*
X240483Y-369739D01*
X240531Y-369717D01*
X240576Y-369698D01*
X240616Y-369683D01*
X240650Y-369672D01*
X240679Y-369661D01*
X240701Y-369654D01*
X240716Y-369650D01*
X240720D01*
X240805Y-369990D01*
D02*
G37*
G36*
X252808Y-365685D02*
X252868D01*
X252927Y-365689D01*
X252978Y-365696D01*
X253030Y-365700D01*
X253075Y-365704D01*
X253115Y-365711D01*
X253152Y-365715D01*
X253186Y-365722D01*
X253211Y-365726D01*
X253234Y-365730D01*
X253252Y-365733D01*
X253263Y-365737D01*
X253271Y-365741D01*
X253274D01*
X253356Y-365763D01*
X253430Y-365789D01*
X253493Y-365819D01*
X253548Y-365841D01*
X253596Y-365867D01*
X253630Y-365881D01*
X253648Y-365896D01*
X253656Y-365900D01*
X253711Y-365941D01*
X253759Y-365981D01*
X253800Y-366026D01*
X253837Y-366066D01*
X253863Y-366103D01*
X253881Y-366133D01*
X253892Y-366151D01*
X253896Y-366155D01*
Y-366159D01*
X253926Y-366218D01*
X253944Y-366281D01*
X253959Y-366340D01*
X253970Y-366396D01*
X253977Y-366444D01*
X253981Y-366484D01*
Y-366518D01*
X253974Y-366618D01*
X253959Y-366710D01*
X253933Y-366788D01*
X253907Y-366855D01*
X253878Y-366910D01*
X253866Y-366932D01*
X253852Y-366951D01*
X253844Y-366966D01*
X253837Y-366977D01*
X253829Y-366980D01*
Y-366984D01*
X253770Y-367051D01*
X253700Y-367106D01*
X253630Y-367154D01*
X253563Y-367191D01*
X253500Y-367221D01*
X253474Y-367236D01*
X253448Y-367243D01*
X253430Y-367250D01*
X253415Y-367258D01*
X253408Y-367262D01*
X253404D01*
X253348Y-367276D01*
X253293Y-367291D01*
X253171Y-367313D01*
X253049Y-367332D01*
X252934Y-367343D01*
X252878Y-367347D01*
X252831Y-367350D01*
X252786D01*
X252745Y-367354D01*
X252716D01*
X252690D01*
X252675D01*
X252671D01*
X252542Y-367350D01*
X252420Y-367343D01*
X252309Y-367332D01*
X252205Y-367313D01*
X252109Y-367295D01*
X252024Y-367273D01*
X251946Y-367250D01*
X251880Y-367228D01*
X251820Y-367206D01*
X251769Y-367180D01*
X251724Y-367162D01*
X251691Y-367143D01*
X251661Y-367125D01*
X251643Y-367113D01*
X251632Y-367106D01*
X251628Y-367102D01*
X251584Y-367062D01*
X251543Y-367017D01*
X251506Y-366969D01*
X251476Y-366921D01*
X251450Y-366873D01*
X251428Y-366825D01*
X251413Y-366777D01*
X251398Y-366732D01*
X251387Y-366688D01*
X251380Y-366647D01*
X251373Y-366610D01*
X251369Y-366581D01*
X251365Y-366555D01*
Y-366518D01*
X251373Y-366418D01*
X251387Y-366325D01*
X251413Y-366248D01*
X251439Y-366181D01*
X251465Y-366126D01*
X251480Y-366107D01*
X251491Y-366089D01*
X251499Y-366074D01*
X251506Y-366063D01*
X251513Y-366059D01*
Y-366055D01*
X251576Y-365989D01*
X251643Y-365933D01*
X251717Y-365885D01*
X251783Y-365848D01*
X251846Y-365819D01*
X251872Y-365804D01*
X251898Y-365796D01*
X251917Y-365789D01*
X251931Y-365781D01*
X251939Y-365778D01*
X251942D01*
X251998Y-365759D01*
X252053Y-365744D01*
X252172Y-365722D01*
X252294Y-365704D01*
X252412Y-365693D01*
X252464Y-365689D01*
X252512Y-365685D01*
X252557D01*
X252597Y-365682D01*
X252627D01*
X252653D01*
X252668D01*
X252671D01*
X252742D01*
X252808Y-365685D01*
D02*
G37*
G36*
X252342Y-367650D02*
X252405Y-367657D01*
X252468Y-367669D01*
X252523Y-367683D01*
X252575Y-367702D01*
X252627Y-367720D01*
X252671Y-367742D01*
X252712Y-367761D01*
X252749Y-367783D01*
X252782Y-367805D01*
X252808Y-367824D01*
X252834Y-367842D01*
X252853Y-367857D01*
X252864Y-367868D01*
X252871Y-367876D01*
X252875Y-367879D01*
X252916Y-367924D01*
X252953Y-367968D01*
X252982Y-368016D01*
X253008Y-368064D01*
X253034Y-368112D01*
X253052Y-368161D01*
X253078Y-368249D01*
X253089Y-368290D01*
X253097Y-368327D01*
X253101Y-368360D01*
X253104Y-368390D01*
X253108Y-368412D01*
Y-368494D01*
X253101Y-368538D01*
X253082Y-368627D01*
X253056Y-368708D01*
X253027Y-368782D01*
X252997Y-368841D01*
X252982Y-368867D01*
X252971Y-368889D01*
X252960Y-368908D01*
X252953Y-368919D01*
X252949Y-368927D01*
X252945Y-368930D01*
X253637Y-368793D01*
Y-367768D01*
X253937D01*
Y-369041D01*
X252620Y-369289D01*
X252579Y-368993D01*
X252620Y-368967D01*
X252653Y-368934D01*
X252686Y-368904D01*
X252712Y-368875D01*
X252730Y-368845D01*
X252749Y-368823D01*
X252756Y-368808D01*
X252760Y-368804D01*
X252782Y-368756D01*
X252801Y-368708D01*
X252812Y-368664D01*
X252823Y-368619D01*
X252827Y-368582D01*
X252831Y-368553D01*
Y-368482D01*
X252823Y-368438D01*
X252805Y-368360D01*
X252779Y-368294D01*
X252753Y-368235D01*
X252723Y-368190D01*
X252697Y-368157D01*
X252679Y-368138D01*
X252675Y-368131D01*
X252671D01*
X252608Y-368079D01*
X252542Y-368042D01*
X252471Y-368016D01*
X252401Y-367998D01*
X252342Y-367987D01*
X252316Y-367983D01*
X252294D01*
X252275Y-367979D01*
X252261D01*
X252253D01*
X252250D01*
X252198D01*
X252150Y-367987D01*
X252057Y-368005D01*
X251979Y-368031D01*
X251917Y-368057D01*
X251865Y-368087D01*
X251824Y-368112D01*
X251813Y-368124D01*
X251802Y-368131D01*
X251798Y-368135D01*
X251795Y-368138D01*
X251765Y-368168D01*
X251739Y-368198D01*
X251694Y-368264D01*
X251665Y-368327D01*
X251646Y-368390D01*
X251632Y-368442D01*
X251628Y-368486D01*
X251624Y-368501D01*
Y-368523D01*
X251628Y-368594D01*
X251643Y-368656D01*
X251661Y-368712D01*
X251683Y-368756D01*
X251706Y-368797D01*
X251724Y-368827D01*
X251739Y-368841D01*
X251743Y-368849D01*
X251795Y-368893D01*
X251850Y-368930D01*
X251913Y-368960D01*
X251968Y-368982D01*
X252024Y-368997D01*
X252065Y-369008D01*
X252083Y-369012D01*
X252094Y-369015D01*
X252101D01*
X252105D01*
X252079Y-369345D01*
X252020Y-369337D01*
X251965Y-369326D01*
X251861Y-369293D01*
X251772Y-369252D01*
X251732Y-369230D01*
X251698Y-369208D01*
X251665Y-369189D01*
X251635Y-369167D01*
X251613Y-369148D01*
X251595Y-369130D01*
X251580Y-369115D01*
X251565Y-369108D01*
X251561Y-369100D01*
X251558Y-369097D01*
X251524Y-369052D01*
X251495Y-369008D01*
X251469Y-368960D01*
X251447Y-368912D01*
X251413Y-368819D01*
X251391Y-368727D01*
X251380Y-368686D01*
X251376Y-368645D01*
X251373Y-368612D01*
X251369Y-368582D01*
X251365Y-368556D01*
Y-368523D01*
X251369Y-368445D01*
X251380Y-368372D01*
X251395Y-368301D01*
X251413Y-368238D01*
X251439Y-368179D01*
X251465Y-368124D01*
X251491Y-368072D01*
X251521Y-368027D01*
X251550Y-367987D01*
X251576Y-367950D01*
X251606Y-367920D01*
X251628Y-367894D01*
X251646Y-367876D01*
X251661Y-367861D01*
X251672Y-367853D01*
X251676Y-367850D01*
X251724Y-367813D01*
X251776Y-367783D01*
X251824Y-367754D01*
X251876Y-367731D01*
X251976Y-367694D01*
X252072Y-367672D01*
X252113Y-367665D01*
X252153Y-367657D01*
X252187Y-367654D01*
X252216Y-367650D01*
X252242Y-367646D01*
X252261D01*
X252272D01*
X252275D01*
X252342Y-367650D01*
D02*
G37*
G36*
X252305Y-369974D02*
X252246Y-369988D01*
X252190Y-370007D01*
X252138Y-370025D01*
X252091Y-370044D01*
X252046Y-370066D01*
X252009Y-370088D01*
X251972Y-370114D01*
X251939Y-370136D01*
X251909Y-370155D01*
X251887Y-370177D01*
X251865Y-370196D01*
X251846Y-370210D01*
X251835Y-370225D01*
X251824Y-370236D01*
X251820Y-370240D01*
X251817Y-370244D01*
X251787Y-370281D01*
X251765Y-370321D01*
X251724Y-370403D01*
X251694Y-370480D01*
X251676Y-370558D01*
X251661Y-370625D01*
X251658Y-370651D01*
Y-370677D01*
X251654Y-370699D01*
Y-370725D01*
X251658Y-370810D01*
X251672Y-370891D01*
X251691Y-370965D01*
X251713Y-371032D01*
X251735Y-371084D01*
X251746Y-371106D01*
X251754Y-371124D01*
X251761Y-371139D01*
X251769Y-371150D01*
X251772Y-371158D01*
Y-371161D01*
X251824Y-371232D01*
X251880Y-371291D01*
X251942Y-371343D01*
X252002Y-371383D01*
X252053Y-371417D01*
X252098Y-371439D01*
X252116Y-371446D01*
X252127Y-371454D01*
X252135Y-371457D01*
X252138D01*
X252235Y-371487D01*
X252331Y-371509D01*
X252427Y-371528D01*
X252516Y-371539D01*
X252557Y-371542D01*
X252594Y-371546D01*
X252627D01*
X252653Y-371550D01*
X252675D01*
X252694D01*
X252705D01*
X252708D01*
X252805Y-371546D01*
X252893Y-371539D01*
X252975Y-371524D01*
X253049Y-371509D01*
X253112Y-371498D01*
X253138Y-371491D01*
X253160Y-371483D01*
X253178Y-371480D01*
X253189Y-371476D01*
X253197Y-371472D01*
X253201D01*
X253286Y-371435D01*
X253363Y-371394D01*
X253426Y-371350D01*
X253482Y-371302D01*
X253526Y-371261D01*
X253556Y-371228D01*
X253574Y-371202D01*
X253582Y-371198D01*
Y-371195D01*
X253630Y-371117D01*
X253667Y-371032D01*
X253693Y-370950D01*
X253707Y-370873D01*
X253718Y-370802D01*
X253722Y-370773D01*
Y-370747D01*
X253726Y-370728D01*
Y-370699D01*
X253722Y-370606D01*
X253707Y-370521D01*
X253685Y-370451D01*
X253663Y-370388D01*
X253637Y-370340D01*
X253619Y-370303D01*
X253604Y-370281D01*
X253596Y-370273D01*
X253541Y-370214D01*
X253478Y-370159D01*
X253411Y-370114D01*
X253345Y-370077D01*
X253286Y-370048D01*
X253256Y-370037D01*
X253234Y-370029D01*
X253215Y-370022D01*
X253201Y-370014D01*
X253193Y-370011D01*
X253189D01*
X253267Y-369678D01*
X253334Y-369700D01*
X253393Y-369722D01*
X253448Y-369752D01*
X253504Y-369777D01*
X253552Y-369807D01*
X253596Y-369840D01*
X253641Y-369870D01*
X253678Y-369900D01*
X253707Y-369929D01*
X253737Y-369955D01*
X253763Y-369981D01*
X253781Y-370000D01*
X253800Y-370018D01*
X253811Y-370033D01*
X253815Y-370040D01*
X253818Y-370044D01*
X253852Y-370096D01*
X253885Y-370147D01*
X253911Y-370199D01*
X253933Y-370255D01*
X253966Y-370366D01*
X253989Y-370466D01*
X254000Y-370514D01*
X254003Y-370554D01*
X254007Y-370595D01*
X254011Y-370628D01*
X254014Y-370654D01*
Y-370691D01*
X254007Y-370813D01*
X253989Y-370932D01*
X253966Y-371036D01*
X253952Y-371084D01*
X253937Y-371128D01*
X253922Y-371169D01*
X253907Y-371206D01*
X253896Y-371235D01*
X253885Y-371265D01*
X253874Y-371283D01*
X253866Y-371298D01*
X253863Y-371309D01*
X253859Y-371313D01*
X253796Y-371413D01*
X253722Y-371498D01*
X253648Y-371572D01*
X253574Y-371635D01*
X253507Y-371683D01*
X253478Y-371702D01*
X253452Y-371716D01*
X253434Y-371731D01*
X253419Y-371739D01*
X253408Y-371742D01*
X253404Y-371746D01*
X253289Y-371798D01*
X253171Y-371835D01*
X253052Y-371861D01*
X252945Y-371879D01*
X252897Y-371886D01*
X252849Y-371890D01*
X252812Y-371894D01*
X252775D01*
X252749Y-371898D01*
X252727D01*
X252712D01*
X252708D01*
X252575Y-371890D01*
X252446Y-371875D01*
X252331Y-371857D01*
X252275Y-371842D01*
X252227Y-371831D01*
X252183Y-371820D01*
X252142Y-371805D01*
X252105Y-371794D01*
X252076Y-371787D01*
X252053Y-371776D01*
X252035Y-371772D01*
X252024Y-371764D01*
X252020D01*
X251909Y-371709D01*
X251809Y-371646D01*
X251724Y-371579D01*
X251691Y-371546D01*
X251658Y-371516D01*
X251628Y-371487D01*
X251602Y-371457D01*
X251580Y-371431D01*
X251565Y-371409D01*
X251550Y-371394D01*
X251539Y-371380D01*
X251535Y-371372D01*
X251532Y-371369D01*
X251502Y-371317D01*
X251476Y-371265D01*
X251436Y-371154D01*
X251406Y-371043D01*
X251387Y-370936D01*
X251380Y-370884D01*
X251373Y-370839D01*
X251369Y-370799D01*
Y-370765D01*
X251365Y-370736D01*
Y-370695D01*
X251369Y-370621D01*
X251376Y-370551D01*
X251384Y-370484D01*
X251398Y-370421D01*
X251417Y-370362D01*
X251436Y-370307D01*
X251454Y-370255D01*
X251476Y-370207D01*
X251495Y-370166D01*
X251513Y-370125D01*
X251532Y-370096D01*
X251550Y-370066D01*
X251565Y-370048D01*
X251572Y-370029D01*
X251580Y-370022D01*
X251584Y-370018D01*
X251628Y-369966D01*
X251672Y-369922D01*
X251724Y-369881D01*
X251776Y-369840D01*
X251880Y-369774D01*
X251983Y-369722D01*
X252031Y-369700D01*
X252076Y-369681D01*
X252116Y-369667D01*
X252150Y-369655D01*
X252179Y-369644D01*
X252202Y-369637D01*
X252216Y-369633D01*
X252220D01*
X252305Y-369974D01*
D02*
G37*
G36*
X258232Y-377940D02*
X258169Y-377977D01*
X258110Y-378017D01*
X258051Y-378065D01*
X257999Y-378110D01*
X257955Y-378154D01*
X257918Y-378188D01*
X257907Y-378202D01*
X257896Y-378214D01*
X257892Y-378217D01*
X257888Y-378221D01*
X257825Y-378299D01*
X257766Y-378376D01*
X257714Y-378450D01*
X257674Y-378524D01*
X257636Y-378587D01*
X257622Y-378613D01*
X257611Y-378635D01*
X257599Y-378654D01*
X257596Y-378669D01*
X257589Y-378676D01*
Y-378680D01*
X257285D01*
X257307Y-378624D01*
X257333Y-378569D01*
X257359Y-378513D01*
X257385Y-378461D01*
X257407Y-378417D01*
X257426Y-378380D01*
X257440Y-378358D01*
X257444Y-378354D01*
Y-378350D01*
X257485Y-378284D01*
X257526Y-378225D01*
X257563Y-378173D01*
X257596Y-378132D01*
X257622Y-378095D01*
X257644Y-378073D01*
X257659Y-378054D01*
X257662Y-378051D01*
X255661D01*
Y-377736D01*
X258232D01*
Y-377940D01*
D02*
G37*
G36*
X256593Y-379216D02*
X256656Y-379224D01*
X256719Y-379235D01*
X256774Y-379250D01*
X256826Y-379268D01*
X256878Y-379287D01*
X256922Y-379309D01*
X256963Y-379327D01*
X257000Y-379349D01*
X257033Y-379372D01*
X257059Y-379390D01*
X257085Y-379409D01*
X257104Y-379423D01*
X257115Y-379434D01*
X257122Y-379442D01*
X257126Y-379446D01*
X257167Y-379490D01*
X257204Y-379534D01*
X257233Y-379583D01*
X257259Y-379631D01*
X257285Y-379679D01*
X257304Y-379727D01*
X257329Y-379816D01*
X257341Y-379856D01*
X257348Y-379893D01*
X257352Y-379927D01*
X257355Y-379956D01*
X257359Y-379978D01*
Y-380060D01*
X257352Y-380104D01*
X257333Y-380193D01*
X257307Y-380274D01*
X257278Y-380348D01*
X257248Y-380408D01*
X257233Y-380434D01*
X257222Y-380456D01*
X257211Y-380474D01*
X257204Y-380485D01*
X257200Y-380493D01*
X257196Y-380496D01*
X257888Y-380360D01*
Y-379335D01*
X258188D01*
Y-380607D01*
X256871Y-380855D01*
X256830Y-380559D01*
X256871Y-380533D01*
X256904Y-380500D01*
X256937Y-380470D01*
X256963Y-380441D01*
X256982Y-380411D01*
X257000Y-380389D01*
X257008Y-380374D01*
X257011Y-380371D01*
X257033Y-380323D01*
X257052Y-380274D01*
X257063Y-380230D01*
X257074Y-380186D01*
X257078Y-380149D01*
X257082Y-380119D01*
Y-380049D01*
X257074Y-380004D01*
X257056Y-379927D01*
X257030Y-379860D01*
X257004Y-379801D01*
X256974Y-379756D01*
X256948Y-379723D01*
X256930Y-379705D01*
X256926Y-379697D01*
X256922D01*
X256859Y-379645D01*
X256793Y-379608D01*
X256723Y-379583D01*
X256652Y-379564D01*
X256593Y-379553D01*
X256567Y-379549D01*
X256545D01*
X256526Y-379545D01*
X256512D01*
X256504D01*
X256501D01*
X256449D01*
X256401Y-379553D01*
X256308Y-379571D01*
X256230Y-379597D01*
X256168Y-379623D01*
X256116Y-379653D01*
X256075Y-379679D01*
X256064Y-379690D01*
X256053Y-379697D01*
X256049Y-379701D01*
X256046Y-379705D01*
X256016Y-379734D01*
X255990Y-379764D01*
X255946Y-379830D01*
X255916Y-379893D01*
X255898Y-379956D01*
X255883Y-380008D01*
X255879Y-380052D01*
X255875Y-380067D01*
Y-380089D01*
X255879Y-380160D01*
X255894Y-380223D01*
X255912Y-380278D01*
X255935Y-380323D01*
X255957Y-380363D01*
X255975Y-380393D01*
X255990Y-380408D01*
X255994Y-380415D01*
X256046Y-380459D01*
X256101Y-380496D01*
X256164Y-380526D01*
X256220Y-380548D01*
X256275Y-380563D01*
X256316Y-380574D01*
X256334Y-380578D01*
X256345Y-380581D01*
X256353D01*
X256356D01*
X256330Y-380911D01*
X256271Y-380903D01*
X256216Y-380892D01*
X256112Y-380859D01*
X256023Y-380818D01*
X255983Y-380796D01*
X255949Y-380774D01*
X255916Y-380755D01*
X255887Y-380733D01*
X255864Y-380715D01*
X255846Y-380696D01*
X255831Y-380681D01*
X255816Y-380674D01*
X255812Y-380667D01*
X255809Y-380663D01*
X255775Y-380619D01*
X255746Y-380574D01*
X255720Y-380526D01*
X255698Y-380478D01*
X255664Y-380385D01*
X255642Y-380293D01*
X255631Y-380252D01*
X255627Y-380211D01*
X255624Y-380178D01*
X255620Y-380149D01*
X255616Y-380123D01*
Y-380089D01*
X255620Y-380012D01*
X255631Y-379938D01*
X255646Y-379867D01*
X255664Y-379804D01*
X255690Y-379745D01*
X255716Y-379690D01*
X255742Y-379638D01*
X255772Y-379594D01*
X255801Y-379553D01*
X255827Y-379516D01*
X255857Y-379486D01*
X255879Y-379460D01*
X255898Y-379442D01*
X255912Y-379427D01*
X255924Y-379420D01*
X255927Y-379416D01*
X255975Y-379379D01*
X256027Y-379349D01*
X256075Y-379320D01*
X256127Y-379298D01*
X256227Y-379261D01*
X256323Y-379238D01*
X256364Y-379231D01*
X256404Y-379224D01*
X256438Y-379220D01*
X256467Y-379216D01*
X256493Y-379212D01*
X256512D01*
X256523D01*
X256526D01*
X256593Y-379216D01*
D02*
G37*
G36*
X256556Y-381540D02*
X256497Y-381555D01*
X256441Y-381573D01*
X256390Y-381592D01*
X256342Y-381610D01*
X256297Y-381632D01*
X256260Y-381655D01*
X256223Y-381680D01*
X256190Y-381703D01*
X256160Y-381721D01*
X256138Y-381743D01*
X256116Y-381762D01*
X256097Y-381777D01*
X256086Y-381791D01*
X256075Y-381803D01*
X256071Y-381806D01*
X256068Y-381810D01*
X256038Y-381847D01*
X256016Y-381888D01*
X255975Y-381969D01*
X255946Y-382047D01*
X255927Y-382124D01*
X255912Y-382191D01*
X255909Y-382217D01*
Y-382243D01*
X255905Y-382265D01*
Y-382291D01*
X255909Y-382376D01*
X255924Y-382457D01*
X255942Y-382531D01*
X255964Y-382598D01*
X255986Y-382650D01*
X255997Y-382672D01*
X256005Y-382691D01*
X256012Y-382705D01*
X256020Y-382716D01*
X256023Y-382724D01*
Y-382728D01*
X256075Y-382798D01*
X256131Y-382857D01*
X256194Y-382909D01*
X256253Y-382949D01*
X256305Y-382983D01*
X256349Y-383005D01*
X256367Y-383012D01*
X256379Y-383020D01*
X256386Y-383024D01*
X256390D01*
X256486Y-383053D01*
X256582Y-383075D01*
X256678Y-383094D01*
X256767Y-383105D01*
X256808Y-383109D01*
X256845Y-383112D01*
X256878D01*
X256904Y-383116D01*
X256926D01*
X256945D01*
X256956D01*
X256960D01*
X257056Y-383112D01*
X257144Y-383105D01*
X257226Y-383090D01*
X257300Y-383075D01*
X257363Y-383064D01*
X257389Y-383057D01*
X257411Y-383049D01*
X257429Y-383046D01*
X257440Y-383042D01*
X257448Y-383038D01*
X257452D01*
X257537Y-383001D01*
X257614Y-382961D01*
X257677Y-382916D01*
X257733Y-382868D01*
X257777Y-382827D01*
X257807Y-382794D01*
X257825Y-382768D01*
X257833Y-382765D01*
Y-382761D01*
X257881Y-382683D01*
X257918Y-382598D01*
X257944Y-382517D01*
X257958Y-382439D01*
X257969Y-382369D01*
X257973Y-382339D01*
Y-382313D01*
X257977Y-382295D01*
Y-382265D01*
X257973Y-382172D01*
X257958Y-382087D01*
X257936Y-382017D01*
X257914Y-381954D01*
X257888Y-381906D01*
X257870Y-381869D01*
X257855Y-381847D01*
X257847Y-381839D01*
X257792Y-381780D01*
X257729Y-381725D01*
X257662Y-381680D01*
X257596Y-381643D01*
X257537Y-381614D01*
X257507Y-381603D01*
X257485Y-381595D01*
X257466Y-381588D01*
X257452Y-381580D01*
X257444Y-381577D01*
X257440D01*
X257518Y-381244D01*
X257585Y-381266D01*
X257644Y-381288D01*
X257699Y-381318D01*
X257755Y-381344D01*
X257803Y-381373D01*
X257847Y-381407D01*
X257892Y-381436D01*
X257929Y-381466D01*
X257958Y-381495D01*
X257988Y-381521D01*
X258014Y-381547D01*
X258032Y-381566D01*
X258051Y-381584D01*
X258062Y-381599D01*
X258066Y-381606D01*
X258069Y-381610D01*
X258103Y-381662D01*
X258136Y-381714D01*
X258162Y-381766D01*
X258184Y-381821D01*
X258218Y-381932D01*
X258240Y-382032D01*
X258251Y-382080D01*
X258254Y-382121D01*
X258258Y-382161D01*
X258262Y-382195D01*
X258265Y-382221D01*
Y-382258D01*
X258258Y-382380D01*
X258240Y-382498D01*
X258218Y-382602D01*
X258203Y-382650D01*
X258188Y-382694D01*
X258173Y-382735D01*
X258158Y-382772D01*
X258147Y-382802D01*
X258136Y-382831D01*
X258125Y-382850D01*
X258118Y-382864D01*
X258114Y-382875D01*
X258110Y-382879D01*
X258047Y-382979D01*
X257973Y-383064D01*
X257899Y-383138D01*
X257825Y-383201D01*
X257759Y-383249D01*
X257729Y-383268D01*
X257703Y-383282D01*
X257685Y-383297D01*
X257670Y-383305D01*
X257659Y-383308D01*
X257655Y-383312D01*
X257540Y-383364D01*
X257422Y-383401D01*
X257304Y-383427D01*
X257196Y-383445D01*
X257148Y-383453D01*
X257100Y-383456D01*
X257063Y-383460D01*
X257026D01*
X257000Y-383464D01*
X256978D01*
X256963D01*
X256960D01*
X256826Y-383456D01*
X256697Y-383442D01*
X256582Y-383423D01*
X256526Y-383408D01*
X256479Y-383397D01*
X256434Y-383386D01*
X256393Y-383371D01*
X256356Y-383360D01*
X256327Y-383353D01*
X256305Y-383342D01*
X256286Y-383338D01*
X256275Y-383331D01*
X256271D01*
X256160Y-383275D01*
X256060Y-383212D01*
X255975Y-383146D01*
X255942Y-383112D01*
X255909Y-383083D01*
X255879Y-383053D01*
X255853Y-383024D01*
X255831Y-382998D01*
X255816Y-382975D01*
X255801Y-382961D01*
X255790Y-382946D01*
X255786Y-382938D01*
X255783Y-382935D01*
X255753Y-382883D01*
X255727Y-382831D01*
X255687Y-382720D01*
X255657Y-382609D01*
X255639Y-382502D01*
X255631Y-382450D01*
X255624Y-382406D01*
X255620Y-382365D01*
Y-382332D01*
X255616Y-382302D01*
Y-382261D01*
X255620Y-382187D01*
X255627Y-382117D01*
X255635Y-382050D01*
X255650Y-381988D01*
X255668Y-381928D01*
X255687Y-381873D01*
X255705Y-381821D01*
X255727Y-381773D01*
X255746Y-381732D01*
X255764Y-381692D01*
X255783Y-381662D01*
X255801Y-381632D01*
X255816Y-381614D01*
X255823Y-381595D01*
X255831Y-381588D01*
X255835Y-381584D01*
X255879Y-381532D01*
X255924Y-381488D01*
X255975Y-381447D01*
X256027Y-381407D01*
X256131Y-381340D01*
X256234Y-381288D01*
X256282Y-381266D01*
X256327Y-381247D01*
X256367Y-381233D01*
X256401Y-381222D01*
X256430Y-381210D01*
X256453Y-381203D01*
X256467Y-381199D01*
X256471D01*
X256556Y-381540D01*
D02*
G37*
G36*
X267713Y-366934D02*
X267776Y-366890D01*
X267802Y-366867D01*
X267828Y-366849D01*
X267850Y-366830D01*
X267865Y-366816D01*
X267876Y-366805D01*
X267880Y-366801D01*
X267898Y-366782D01*
X267916Y-366760D01*
X267965Y-366708D01*
X268020Y-366649D01*
X268076Y-366586D01*
X268124Y-366527D01*
X268146Y-366501D01*
X268168Y-366479D01*
X268183Y-366460D01*
X268194Y-366446D01*
X268201Y-366438D01*
X268205Y-366435D01*
X268257Y-366375D01*
X268305Y-366316D01*
X268353Y-366264D01*
X268394Y-366216D01*
X268435Y-366172D01*
X268472Y-366135D01*
X268505Y-366098D01*
X268534Y-366068D01*
X268564Y-366039D01*
X268586Y-366017D01*
X268605Y-365998D01*
X268623Y-365980D01*
X268645Y-365961D01*
X268653Y-365954D01*
X268716Y-365902D01*
X268771Y-365857D01*
X268827Y-365820D01*
X268871Y-365791D01*
X268912Y-365769D01*
X268941Y-365754D01*
X268960Y-365746D01*
X268967Y-365743D01*
X269023Y-365721D01*
X269078Y-365706D01*
X269130Y-365691D01*
X269175Y-365684D01*
X269215Y-365680D01*
X269245Y-365676D01*
X269263D01*
X269271D01*
X269326Y-365680D01*
X269378Y-365687D01*
X269430Y-365695D01*
X269474Y-365709D01*
X269563Y-365746D01*
X269633Y-365783D01*
X269667Y-365806D01*
X269692Y-365824D01*
X269718Y-365843D01*
X269737Y-365861D01*
X269752Y-365876D01*
X269766Y-365883D01*
X269770Y-365891D01*
X269774Y-365894D01*
X269811Y-365935D01*
X269844Y-365980D01*
X269870Y-366028D01*
X269892Y-366076D01*
X269929Y-366172D01*
X269955Y-366268D01*
X269963Y-366309D01*
X269970Y-366350D01*
X269974Y-366387D01*
X269977Y-366416D01*
X269981Y-366442D01*
Y-366479D01*
X269977Y-366546D01*
X269974Y-366609D01*
X269963Y-366668D01*
X269952Y-366723D01*
X269937Y-366775D01*
X269922Y-366823D01*
X269903Y-366867D01*
X269885Y-366908D01*
X269866Y-366945D01*
X269848Y-366975D01*
X269833Y-367001D01*
X269818Y-367023D01*
X269807Y-367041D01*
X269796Y-367053D01*
X269792Y-367060D01*
X269789Y-367064D01*
X269752Y-367101D01*
X269711Y-367134D01*
X269667Y-367167D01*
X269622Y-367193D01*
X269533Y-367237D01*
X269445Y-367267D01*
X269404Y-367278D01*
X269363Y-367289D01*
X269330Y-367297D01*
X269300Y-367304D01*
X269274Y-367308D01*
X269256D01*
X269245Y-367312D01*
X269241D01*
X269208Y-366990D01*
X269293Y-366982D01*
X269367Y-366967D01*
X269433Y-366945D01*
X269485Y-366919D01*
X269530Y-366897D01*
X269559Y-366875D01*
X269578Y-366860D01*
X269585Y-366853D01*
X269630Y-366797D01*
X269663Y-366738D01*
X269689Y-366675D01*
X269704Y-366620D01*
X269715Y-366568D01*
X269718Y-366523D01*
X269722Y-366509D01*
Y-366486D01*
X269718Y-366409D01*
X269704Y-366338D01*
X269681Y-366279D01*
X269659Y-366227D01*
X269633Y-366187D01*
X269615Y-366161D01*
X269600Y-366142D01*
X269593Y-366135D01*
X269541Y-366090D01*
X269489Y-366057D01*
X269437Y-366031D01*
X269385Y-366017D01*
X269345Y-366005D01*
X269308Y-366002D01*
X269285Y-365998D01*
X269282D01*
X269278D01*
X269212Y-366005D01*
X269141Y-366020D01*
X269078Y-366046D01*
X269019Y-366072D01*
X268971Y-366102D01*
X268930Y-366127D01*
X268916Y-366135D01*
X268904Y-366142D01*
X268901Y-366150D01*
X268897D01*
X268856Y-366179D01*
X268816Y-366216D01*
X268771Y-366257D01*
X268727Y-366301D01*
X268638Y-366394D01*
X268549Y-366486D01*
X268509Y-366534D01*
X268472Y-366575D01*
X268438Y-366616D01*
X268409Y-366649D01*
X268386Y-366675D01*
X268368Y-366697D01*
X268357Y-366712D01*
X268353Y-366716D01*
X268275Y-366808D01*
X268201Y-366893D01*
X268135Y-366964D01*
X268079Y-367019D01*
X268031Y-367067D01*
X267998Y-367101D01*
X267976Y-367119D01*
X267972Y-367126D01*
X267968D01*
X267905Y-367178D01*
X267846Y-367219D01*
X267787Y-367256D01*
X267735Y-367286D01*
X267691Y-367308D01*
X267657Y-367323D01*
X267635Y-367330D01*
X267632Y-367334D01*
X267628D01*
X267587Y-367349D01*
X267550Y-367356D01*
X267513Y-367363D01*
X267480Y-367367D01*
X267450Y-367371D01*
X267428D01*
X267413D01*
X267410D01*
Y-365672D01*
X267713D01*
Y-366934D01*
D02*
G37*
G36*
X268342Y-367622D02*
X268405Y-367630D01*
X268468Y-367641D01*
X268523Y-367656D01*
X268575Y-367674D01*
X268627Y-367693D01*
X268671Y-367715D01*
X268712Y-367733D01*
X268749Y-367756D01*
X268782Y-367778D01*
X268808Y-367796D01*
X268834Y-367815D01*
X268853Y-367829D01*
X268864Y-367841D01*
X268871Y-367848D01*
X268875Y-367852D01*
X268916Y-367896D01*
X268952Y-367940D01*
X268982Y-367989D01*
X269008Y-368037D01*
X269034Y-368085D01*
X269052Y-368133D01*
X269078Y-368222D01*
X269089Y-368262D01*
X269097Y-368299D01*
X269100Y-368333D01*
X269104Y-368362D01*
X269108Y-368385D01*
Y-368466D01*
X269100Y-368510D01*
X269082Y-368599D01*
X269056Y-368681D01*
X269026Y-368755D01*
X268997Y-368814D01*
X268982Y-368840D01*
X268971Y-368862D01*
X268960Y-368880D01*
X268952Y-368891D01*
X268949Y-368899D01*
X268945Y-368902D01*
X269637Y-368766D01*
Y-367741D01*
X269937D01*
Y-369014D01*
X268619Y-369261D01*
X268579Y-368965D01*
X268619Y-368939D01*
X268653Y-368906D01*
X268686Y-368877D01*
X268712Y-368847D01*
X268730Y-368817D01*
X268749Y-368795D01*
X268756Y-368780D01*
X268760Y-368777D01*
X268782Y-368729D01*
X268801Y-368681D01*
X268812Y-368636D01*
X268823Y-368592D01*
X268827Y-368555D01*
X268830Y-368525D01*
Y-368455D01*
X268823Y-368410D01*
X268805Y-368333D01*
X268779Y-368266D01*
X268753Y-368207D01*
X268723Y-368162D01*
X268697Y-368129D01*
X268679Y-368111D01*
X268675Y-368103D01*
X268671D01*
X268608Y-368052D01*
X268542Y-368015D01*
X268472Y-367989D01*
X268401Y-367970D01*
X268342Y-367959D01*
X268316Y-367955D01*
X268294D01*
X268275Y-367952D01*
X268261D01*
X268253D01*
X268250D01*
X268198D01*
X268150Y-367959D01*
X268057Y-367977D01*
X267979Y-368003D01*
X267916Y-368029D01*
X267865Y-368059D01*
X267824Y-368085D01*
X267813Y-368096D01*
X267802Y-368103D01*
X267798Y-368107D01*
X267794Y-368111D01*
X267765Y-368140D01*
X267739Y-368170D01*
X267694Y-368236D01*
X267665Y-368299D01*
X267646Y-368362D01*
X267632Y-368414D01*
X267628Y-368459D01*
X267624Y-368473D01*
Y-368495D01*
X267628Y-368566D01*
X267643Y-368629D01*
X267661Y-368684D01*
X267683Y-368729D01*
X267706Y-368769D01*
X267724Y-368799D01*
X267739Y-368814D01*
X267743Y-368821D01*
X267794Y-368865D01*
X267850Y-368902D01*
X267913Y-368932D01*
X267968Y-368954D01*
X268024Y-368969D01*
X268064Y-368980D01*
X268083Y-368984D01*
X268094Y-368988D01*
X268102D01*
X268105D01*
X268079Y-369317D01*
X268020Y-369309D01*
X267965Y-369298D01*
X267861Y-369265D01*
X267772Y-369224D01*
X267731Y-369202D01*
X267698Y-369180D01*
X267665Y-369162D01*
X267635Y-369139D01*
X267613Y-369121D01*
X267595Y-369102D01*
X267580Y-369088D01*
X267565Y-369080D01*
X267561Y-369073D01*
X267558Y-369069D01*
X267524Y-369025D01*
X267495Y-368980D01*
X267469Y-368932D01*
X267447Y-368884D01*
X267413Y-368792D01*
X267391Y-368699D01*
X267380Y-368658D01*
X267376Y-368618D01*
X267373Y-368584D01*
X267369Y-368555D01*
X267365Y-368529D01*
Y-368495D01*
X267369Y-368418D01*
X267380Y-368344D01*
X267395Y-368273D01*
X267413Y-368211D01*
X267439Y-368151D01*
X267465Y-368096D01*
X267491Y-368044D01*
X267521Y-368000D01*
X267550Y-367959D01*
X267576Y-367922D01*
X267606Y-367892D01*
X267628Y-367866D01*
X267646Y-367848D01*
X267661Y-367833D01*
X267672Y-367826D01*
X267676Y-367822D01*
X267724Y-367785D01*
X267776Y-367756D01*
X267824Y-367726D01*
X267876Y-367704D01*
X267976Y-367667D01*
X268072Y-367645D01*
X268113Y-367637D01*
X268153Y-367630D01*
X268187Y-367626D01*
X268216Y-367622D01*
X268242Y-367619D01*
X268261D01*
X268272D01*
X268275D01*
X268342Y-367622D01*
D02*
G37*
G36*
X268305Y-369946D02*
X268246Y-369961D01*
X268190Y-369979D01*
X268139Y-369998D01*
X268090Y-370016D01*
X268046Y-370038D01*
X268009Y-370061D01*
X267972Y-370087D01*
X267939Y-370109D01*
X267909Y-370127D01*
X267887Y-370149D01*
X267865Y-370168D01*
X267846Y-370183D01*
X267835Y-370198D01*
X267824Y-370209D01*
X267820Y-370212D01*
X267817Y-370216D01*
X267787Y-370253D01*
X267765Y-370294D01*
X267724Y-370375D01*
X267694Y-370453D01*
X267676Y-370531D01*
X267661Y-370597D01*
X267657Y-370623D01*
Y-370649D01*
X267654Y-370671D01*
Y-370697D01*
X267657Y-370782D01*
X267672Y-370864D01*
X267691Y-370937D01*
X267713Y-371004D01*
X267735Y-371056D01*
X267746Y-371078D01*
X267754Y-371097D01*
X267761Y-371111D01*
X267769Y-371123D01*
X267772Y-371130D01*
Y-371134D01*
X267824Y-371204D01*
X267880Y-371263D01*
X267942Y-371315D01*
X268002Y-371356D01*
X268053Y-371389D01*
X268098Y-371411D01*
X268116Y-371418D01*
X268127Y-371426D01*
X268135Y-371430D01*
X268139D01*
X268235Y-371459D01*
X268331Y-371481D01*
X268427Y-371500D01*
X268516Y-371511D01*
X268557Y-371515D01*
X268594Y-371518D01*
X268627D01*
X268653Y-371522D01*
X268675D01*
X268693D01*
X268705D01*
X268708D01*
X268805Y-371518D01*
X268893Y-371511D01*
X268975Y-371496D01*
X269049Y-371481D01*
X269112Y-371470D01*
X269138Y-371463D01*
X269160Y-371456D01*
X269178Y-371452D01*
X269189Y-371448D01*
X269197Y-371444D01*
X269200D01*
X269285Y-371407D01*
X269363Y-371367D01*
X269426Y-371322D01*
X269482Y-371274D01*
X269526Y-371234D01*
X269556Y-371200D01*
X269574Y-371174D01*
X269582Y-371171D01*
Y-371167D01*
X269630Y-371089D01*
X269667Y-371004D01*
X269692Y-370923D01*
X269707Y-370845D01*
X269718Y-370775D01*
X269722Y-370745D01*
Y-370719D01*
X269726Y-370701D01*
Y-370671D01*
X269722Y-370579D01*
X269707Y-370494D01*
X269685Y-370423D01*
X269663Y-370360D01*
X269637Y-370312D01*
X269619Y-370275D01*
X269604Y-370253D01*
X269596Y-370246D01*
X269541Y-370186D01*
X269478Y-370131D01*
X269411Y-370087D01*
X269345Y-370050D01*
X269285Y-370020D01*
X269256Y-370009D01*
X269234Y-370001D01*
X269215Y-369994D01*
X269200Y-369987D01*
X269193Y-369983D01*
X269189D01*
X269267Y-369650D01*
X269334Y-369672D01*
X269393Y-369694D01*
X269448Y-369724D01*
X269504Y-369750D01*
X269552Y-369779D01*
X269596Y-369813D01*
X269641Y-369842D01*
X269678Y-369872D01*
X269707Y-369901D01*
X269737Y-369927D01*
X269763Y-369953D01*
X269781Y-369972D01*
X269800Y-369990D01*
X269811Y-370005D01*
X269815Y-370012D01*
X269818Y-370016D01*
X269852Y-370068D01*
X269885Y-370120D01*
X269911Y-370172D01*
X269933Y-370227D01*
X269966Y-370338D01*
X269988Y-370438D01*
X270000Y-370486D01*
X270003Y-370527D01*
X270007Y-370567D01*
X270011Y-370601D01*
X270014Y-370627D01*
Y-370664D01*
X270007Y-370786D01*
X269988Y-370904D01*
X269966Y-371008D01*
X269952Y-371056D01*
X269937Y-371100D01*
X269922Y-371141D01*
X269907Y-371178D01*
X269896Y-371208D01*
X269885Y-371237D01*
X269874Y-371256D01*
X269866Y-371270D01*
X269863Y-371282D01*
X269859Y-371285D01*
X269796Y-371385D01*
X269722Y-371470D01*
X269648Y-371544D01*
X269574Y-371607D01*
X269508Y-371655D01*
X269478Y-371674D01*
X269452Y-371689D01*
X269433Y-371703D01*
X269419Y-371711D01*
X269408Y-371714D01*
X269404Y-371718D01*
X269289Y-371770D01*
X269171Y-371807D01*
X269052Y-371833D01*
X268945Y-371851D01*
X268897Y-371859D01*
X268849Y-371863D01*
X268812Y-371866D01*
X268775D01*
X268749Y-371870D01*
X268727D01*
X268712D01*
X268708D01*
X268575Y-371863D01*
X268446Y-371848D01*
X268331Y-371829D01*
X268275Y-371814D01*
X268227Y-371803D01*
X268183Y-371792D01*
X268142Y-371777D01*
X268105Y-371766D01*
X268076Y-371759D01*
X268053Y-371748D01*
X268035Y-371744D01*
X268024Y-371737D01*
X268020D01*
X267909Y-371681D01*
X267809Y-371618D01*
X267724Y-371552D01*
X267691Y-371518D01*
X267657Y-371489D01*
X267628Y-371459D01*
X267602Y-371430D01*
X267580Y-371404D01*
X267565Y-371381D01*
X267550Y-371367D01*
X267539Y-371352D01*
X267535Y-371344D01*
X267532Y-371341D01*
X267502Y-371289D01*
X267476Y-371237D01*
X267436Y-371126D01*
X267406Y-371015D01*
X267387Y-370908D01*
X267380Y-370856D01*
X267373Y-370812D01*
X267369Y-370771D01*
Y-370738D01*
X267365Y-370708D01*
Y-370667D01*
X267369Y-370593D01*
X267376Y-370523D01*
X267384Y-370457D01*
X267399Y-370394D01*
X267417Y-370334D01*
X267436Y-370279D01*
X267454Y-370227D01*
X267476Y-370179D01*
X267495Y-370138D01*
X267513Y-370098D01*
X267532Y-370068D01*
X267550Y-370038D01*
X267565Y-370020D01*
X267572Y-370001D01*
X267580Y-369994D01*
X267583Y-369990D01*
X267628Y-369938D01*
X267672Y-369894D01*
X267724Y-369853D01*
X267776Y-369813D01*
X267880Y-369746D01*
X267983Y-369694D01*
X268031Y-369672D01*
X268076Y-369654D01*
X268116Y-369639D01*
X268150Y-369628D01*
X268179Y-369617D01*
X268201Y-369609D01*
X268216Y-369605D01*
X268220D01*
X268305Y-369946D01*
D02*
G37*
G36*
X622927Y-125690D02*
X621943D01*
X621876Y-125686D01*
X621802Y-125682D01*
X621728Y-125675D01*
X621654Y-125664D01*
X621591Y-125653D01*
X621588D01*
X621580Y-125649D01*
X621569D01*
X621554Y-125642D01*
X621514Y-125630D01*
X621462Y-125612D01*
X621403Y-125586D01*
X621340Y-125553D01*
X621277Y-125516D01*
X621218Y-125468D01*
X621214Y-125464D01*
X621210Y-125460D01*
X621199Y-125449D01*
X621184Y-125438D01*
X621147Y-125401D01*
X621103Y-125349D01*
X621055Y-125286D01*
X621003Y-125212D01*
X620955Y-125127D01*
X620914Y-125031D01*
Y-125027D01*
X620911Y-125020D01*
X620903Y-125005D01*
X620899Y-124983D01*
X620888Y-124957D01*
X620881Y-124927D01*
X620873Y-124894D01*
X620862Y-124853D01*
X620851Y-124813D01*
X620844Y-124765D01*
X620825Y-124661D01*
X620814Y-124546D01*
X620811Y-124421D01*
Y-124417D01*
Y-124409D01*
Y-124391D01*
Y-124372D01*
X620814Y-124347D01*
Y-124317D01*
X620818Y-124247D01*
X620829Y-124165D01*
X620840Y-124080D01*
X620859Y-123991D01*
X620881Y-123902D01*
Y-123899D01*
X620885Y-123891D01*
X620888Y-123880D01*
X620892Y-123866D01*
X620907Y-123825D01*
X620929Y-123773D01*
X620951Y-123714D01*
X620981Y-123655D01*
X621018Y-123592D01*
X621055Y-123532D01*
X621059Y-123525D01*
X621073Y-123507D01*
X621096Y-123481D01*
X621125Y-123448D01*
X621158Y-123410D01*
X621199Y-123373D01*
X621240Y-123333D01*
X621288Y-123300D01*
X621295Y-123296D01*
X621310Y-123285D01*
X621336Y-123270D01*
X621373Y-123251D01*
X621417Y-123229D01*
X621469Y-123211D01*
X621528Y-123188D01*
X621595Y-123170D01*
X621602D01*
X621614Y-123166D01*
X621625Y-123163D01*
X621662Y-123159D01*
X621713Y-123151D01*
X621773Y-123144D01*
X621843Y-123137D01*
X621921Y-123133D01*
X622006Y-123129D01*
X622927D01*
Y-125690D01*
D02*
G37*
G36*
X619467Y-123743D02*
X620581D01*
Y-124032D01*
X619408Y-125690D01*
X619153D01*
Y-124032D01*
X618805D01*
Y-123743D01*
X619153D01*
Y-123129D01*
X619467D01*
Y-123743D01*
D02*
G37*
G36*
X622831Y-119593D02*
X622516D01*
Y-117591D01*
X622513Y-117595D01*
X622494Y-117610D01*
X622472Y-117632D01*
X622435Y-117658D01*
X622394Y-117691D01*
X622342Y-117728D01*
X622283Y-117769D01*
X622217Y-117809D01*
X622213D01*
X622209Y-117813D01*
X622187Y-117828D01*
X622150Y-117847D01*
X622106Y-117869D01*
X622054Y-117895D01*
X621998Y-117920D01*
X621943Y-117946D01*
X621887Y-117969D01*
Y-117665D01*
X621891D01*
X621899Y-117658D01*
X621913Y-117654D01*
X621932Y-117643D01*
X621954Y-117632D01*
X621980Y-117617D01*
X622043Y-117580D01*
X622117Y-117539D01*
X622191Y-117488D01*
X622268Y-117428D01*
X622346Y-117366D01*
X622350Y-117362D01*
X622354Y-117358D01*
X622365Y-117347D01*
X622379Y-117336D01*
X622413Y-117299D01*
X622457Y-117254D01*
X622502Y-117203D01*
X622550Y-117143D01*
X622590Y-117084D01*
X622627Y-117021D01*
X622831D01*
Y-119593D01*
D02*
G37*
G36*
X620415Y-117036D02*
X620448D01*
X620526Y-117040D01*
X620607Y-117051D01*
X620696Y-117062D01*
X620777Y-117080D01*
X620818Y-117092D01*
X620851Y-117103D01*
X620855D01*
X620859Y-117106D01*
X620881Y-117118D01*
X620914Y-117132D01*
X620955Y-117158D01*
X620999Y-117192D01*
X621047Y-117236D01*
X621092Y-117288D01*
X621136Y-117347D01*
Y-117351D01*
X621140Y-117354D01*
X621155Y-117376D01*
X621170Y-117414D01*
X621192Y-117462D01*
X621210Y-117517D01*
X621229Y-117584D01*
X621240Y-117654D01*
X621244Y-117732D01*
Y-117735D01*
Y-117743D01*
Y-117758D01*
X621240Y-117776D01*
Y-117802D01*
X621236Y-117828D01*
X621221Y-117891D01*
X621199Y-117965D01*
X621170Y-118043D01*
X621125Y-118120D01*
X621096Y-118157D01*
X621066Y-118194D01*
X621062Y-118198D01*
X621059Y-118202D01*
X621047Y-118213D01*
X621033Y-118224D01*
X621014Y-118239D01*
X620992Y-118253D01*
X620962Y-118272D01*
X620933Y-118294D01*
X620896Y-118313D01*
X620855Y-118331D01*
X620811Y-118353D01*
X620763Y-118372D01*
X620707Y-118387D01*
X620652Y-118405D01*
X620589Y-118416D01*
X620522Y-118427D01*
X620530Y-118431D01*
X620544Y-118438D01*
X620567Y-118453D01*
X620596Y-118468D01*
X620663Y-118509D01*
X620696Y-118535D01*
X620726Y-118557D01*
X620733Y-118564D01*
X620751Y-118583D01*
X620781Y-118612D01*
X620818Y-118649D01*
X620859Y-118701D01*
X620907Y-118757D01*
X620955Y-118823D01*
X621007Y-118897D01*
X621447Y-119593D01*
X621025D01*
X620689Y-119060D01*
Y-119056D01*
X620681Y-119049D01*
X620674Y-119038D01*
X620663Y-119023D01*
X620637Y-118982D01*
X620604Y-118930D01*
X620563Y-118875D01*
X620522Y-118816D01*
X620481Y-118760D01*
X620444Y-118709D01*
X620441Y-118705D01*
X620430Y-118690D01*
X620411Y-118668D01*
X620385Y-118642D01*
X620330Y-118586D01*
X620300Y-118561D01*
X620270Y-118538D01*
X620267Y-118535D01*
X620259Y-118531D01*
X620245Y-118524D01*
X620222Y-118512D01*
X620200Y-118501D01*
X620174Y-118490D01*
X620115Y-118472D01*
X620111D01*
X620104Y-118468D01*
X620089D01*
X620071Y-118464D01*
X620045Y-118461D01*
X620015D01*
X619975Y-118457D01*
X619538D01*
Y-119593D01*
X619198D01*
Y-117032D01*
X620385D01*
X620415Y-117036D01*
D02*
G37*
G36*
X542170Y-127101D02*
X542200Y-127105D01*
X542233Y-127109D01*
X542270Y-127116D01*
X542311Y-127123D01*
X542400Y-127146D01*
X542492Y-127183D01*
X542540Y-127205D01*
X542585Y-127231D01*
X542629Y-127264D01*
X542673Y-127297D01*
X542677Y-127301D01*
X542684Y-127308D01*
X542696Y-127320D01*
X542707Y-127334D01*
X542725Y-127353D01*
X542744Y-127379D01*
X542766Y-127405D01*
X542788Y-127438D01*
X542810Y-127475D01*
X542832Y-127512D01*
X542873Y-127601D01*
X542906Y-127704D01*
X542917Y-127760D01*
X542925Y-127819D01*
X542610Y-127860D01*
Y-127856D01*
X542607Y-127849D01*
X542603Y-127834D01*
X542599Y-127815D01*
X542596Y-127793D01*
X542588Y-127767D01*
X542570Y-127712D01*
X542544Y-127645D01*
X542511Y-127582D01*
X542474Y-127523D01*
X542429Y-127471D01*
X542422Y-127468D01*
X542407Y-127453D01*
X542377Y-127434D01*
X542340Y-127416D01*
X542296Y-127394D01*
X542240Y-127375D01*
X542177Y-127360D01*
X542111Y-127357D01*
X542089D01*
X542074Y-127360D01*
X542033Y-127364D01*
X541981Y-127375D01*
X541922Y-127394D01*
X541859Y-127419D01*
X541796Y-127456D01*
X541737Y-127508D01*
X541730Y-127516D01*
X541711Y-127538D01*
X541689Y-127571D01*
X541659Y-127616D01*
X541630Y-127671D01*
X541608Y-127734D01*
X541589Y-127808D01*
X541582Y-127889D01*
Y-127893D01*
Y-127901D01*
Y-127912D01*
X541585Y-127926D01*
X541589Y-127967D01*
X541600Y-128015D01*
X541615Y-128074D01*
X541641Y-128134D01*
X541678Y-128193D01*
X541726Y-128248D01*
X541734Y-128256D01*
X541752Y-128270D01*
X541782Y-128293D01*
X541822Y-128319D01*
X541874Y-128345D01*
X541937Y-128367D01*
X542007Y-128382D01*
X542085Y-128389D01*
X542118D01*
X542144Y-128385D01*
X542177Y-128382D01*
X542214Y-128374D01*
X542259Y-128367D01*
X542307Y-128356D01*
X542270Y-128633D01*
X542251D01*
X542237Y-128629D01*
X542189D01*
X542148Y-128637D01*
X542100Y-128644D01*
X542044Y-128655D01*
X541981Y-128674D01*
X541922Y-128700D01*
X541859Y-128733D01*
X541856D01*
X541852Y-128737D01*
X541833Y-128752D01*
X541808Y-128777D01*
X541778Y-128811D01*
X541748Y-128859D01*
X541722Y-128914D01*
X541704Y-128977D01*
X541697Y-129014D01*
Y-129055D01*
Y-129059D01*
Y-129062D01*
Y-129085D01*
X541704Y-129114D01*
X541711Y-129155D01*
X541726Y-129199D01*
X541745Y-129247D01*
X541774Y-129295D01*
X541815Y-129340D01*
X541819Y-129343D01*
X541837Y-129358D01*
X541863Y-129377D01*
X541896Y-129399D01*
X541941Y-129418D01*
X541993Y-129436D01*
X542052Y-129451D01*
X542118Y-129455D01*
X542148D01*
X542181Y-129447D01*
X542226Y-129440D01*
X542274Y-129425D01*
X542322Y-129406D01*
X542374Y-129377D01*
X542422Y-129340D01*
X542425Y-129336D01*
X542440Y-129318D01*
X542462Y-129292D01*
X542488Y-129255D01*
X542514Y-129207D01*
X542540Y-129147D01*
X542562Y-129077D01*
X542577Y-128996D01*
X542892Y-129051D01*
Y-129055D01*
X542888Y-129066D01*
X542884Y-129081D01*
X542880Y-129103D01*
X542873Y-129129D01*
X542862Y-129158D01*
X542840Y-129229D01*
X542803Y-129310D01*
X542758Y-129392D01*
X542703Y-129469D01*
X542633Y-129540D01*
X542629Y-129543D01*
X542622Y-129547D01*
X542610Y-129554D01*
X542596Y-129566D01*
X542577Y-129580D01*
X542551Y-129595D01*
X542525Y-129610D01*
X542492Y-129628D01*
X542418Y-129658D01*
X542333Y-129688D01*
X542233Y-129706D01*
X542181Y-129713D01*
X542089D01*
X542048Y-129710D01*
X542000Y-129702D01*
X541941Y-129691D01*
X541874Y-129673D01*
X541808Y-129651D01*
X541741Y-129621D01*
X541737D01*
X541734Y-129617D01*
X541711Y-129606D01*
X541678Y-129584D01*
X541641Y-129558D01*
X541597Y-129521D01*
X541552Y-129480D01*
X541508Y-129432D01*
X541471Y-129377D01*
X541467Y-129369D01*
X541456Y-129351D01*
X541441Y-129318D01*
X541423Y-129277D01*
X541404Y-129229D01*
X541389Y-129173D01*
X541378Y-129110D01*
X541375Y-129048D01*
Y-129040D01*
Y-129018D01*
X541378Y-128988D01*
X541386Y-128948D01*
X541397Y-128900D01*
X541415Y-128848D01*
X541437Y-128796D01*
X541467Y-128744D01*
X541471Y-128737D01*
X541482Y-128722D01*
X541504Y-128696D01*
X541534Y-128666D01*
X541571Y-128633D01*
X541615Y-128596D01*
X541667Y-128563D01*
X541730Y-128530D01*
X541726D01*
X541719Y-128526D01*
X541708Y-128522D01*
X541693Y-128518D01*
X541652Y-128504D01*
X541600Y-128481D01*
X541541Y-128452D01*
X541482Y-128415D01*
X541426Y-128367D01*
X541375Y-128311D01*
X541371Y-128304D01*
X541356Y-128282D01*
X541334Y-128245D01*
X541312Y-128197D01*
X541290Y-128137D01*
X541267Y-128067D01*
X541253Y-127986D01*
X541249Y-127897D01*
Y-127893D01*
Y-127882D01*
Y-127864D01*
X541253Y-127841D01*
X541256Y-127812D01*
X541264Y-127778D01*
X541271Y-127741D01*
X541278Y-127701D01*
X541308Y-127612D01*
X541330Y-127564D01*
X541352Y-127519D01*
X541382Y-127471D01*
X541415Y-127423D01*
X541452Y-127375D01*
X541497Y-127331D01*
X541500Y-127327D01*
X541508Y-127320D01*
X541523Y-127308D01*
X541541Y-127294D01*
X541563Y-127275D01*
X541593Y-127257D01*
X541626Y-127234D01*
X541667Y-127216D01*
X541708Y-127194D01*
X541756Y-127172D01*
X541804Y-127153D01*
X541859Y-127135D01*
X541919Y-127120D01*
X541981Y-127109D01*
X542044Y-127101D01*
X542115Y-127098D01*
X542148D01*
X542170Y-127101D01*
D02*
G37*
G36*
X545378Y-129702D02*
X544190D01*
X544161Y-129699D01*
X544127D01*
X544050Y-129695D01*
X543968Y-129684D01*
X543880Y-129673D01*
X543798Y-129654D01*
X543757Y-129643D01*
X543724Y-129632D01*
X543720D01*
X543717Y-129628D01*
X543694Y-129617D01*
X543661Y-129603D01*
X543620Y-129577D01*
X543576Y-129543D01*
X543528Y-129499D01*
X543484Y-129447D01*
X543439Y-129388D01*
Y-129384D01*
X543435Y-129381D01*
X543421Y-129358D01*
X543406Y-129321D01*
X543384Y-129273D01*
X543365Y-129218D01*
X543347Y-129151D01*
X543336Y-129081D01*
X543332Y-129003D01*
Y-128999D01*
Y-128992D01*
Y-128977D01*
X543336Y-128959D01*
Y-128933D01*
X543339Y-128907D01*
X543354Y-128844D01*
X543376Y-128770D01*
X543406Y-128692D01*
X543450Y-128615D01*
X543480Y-128578D01*
X543509Y-128541D01*
X543513Y-128537D01*
X543517Y-128533D01*
X543528Y-128522D01*
X543543Y-128511D01*
X543561Y-128496D01*
X543583Y-128481D01*
X543613Y-128463D01*
X543643Y-128441D01*
X543680Y-128422D01*
X543720Y-128404D01*
X543765Y-128382D01*
X543813Y-128363D01*
X543868Y-128348D01*
X543924Y-128330D01*
X543987Y-128319D01*
X544053Y-128307D01*
X544046Y-128304D01*
X544031Y-128296D01*
X544009Y-128282D01*
X543979Y-128267D01*
X543913Y-128226D01*
X543880Y-128200D01*
X543850Y-128178D01*
X543843Y-128171D01*
X543824Y-128152D01*
X543794Y-128122D01*
X543757Y-128085D01*
X543717Y-128034D01*
X543669Y-127978D01*
X543620Y-127912D01*
X543569Y-127838D01*
X543128Y-127142D01*
X543550D01*
X543887Y-127675D01*
Y-127679D01*
X543894Y-127686D01*
X543902Y-127697D01*
X543913Y-127712D01*
X543939Y-127752D01*
X543972Y-127804D01*
X544013Y-127860D01*
X544053Y-127919D01*
X544094Y-127974D01*
X544131Y-128026D01*
X544135Y-128030D01*
X544146Y-128045D01*
X544164Y-128067D01*
X544190Y-128093D01*
X544246Y-128148D01*
X544275Y-128174D01*
X544305Y-128197D01*
X544309Y-128200D01*
X544316Y-128204D01*
X544331Y-128211D01*
X544353Y-128222D01*
X544375Y-128234D01*
X544401Y-128245D01*
X544460Y-128263D01*
X544464D01*
X544472Y-128267D01*
X544486D01*
X544505Y-128270D01*
X544531Y-128274D01*
X544560D01*
X544601Y-128278D01*
X545038D01*
Y-127142D01*
X545378D01*
Y-129702D01*
D02*
G37*
G36*
X572775Y-136719D02*
X572782Y-136726D01*
X572797Y-136741D01*
X572819Y-136756D01*
X572845Y-136778D01*
X572875Y-136807D01*
X572912Y-136837D01*
X572956Y-136870D01*
X573000Y-136904D01*
X573052Y-136944D01*
X573111Y-136985D01*
X573171Y-137026D01*
X573237Y-137070D01*
X573308Y-137115D01*
X573385Y-137159D01*
X573463Y-137203D01*
X573467Y-137207D01*
X573482Y-137214D01*
X573504Y-137225D01*
X573537Y-137244D01*
X573578Y-137262D01*
X573622Y-137285D01*
X573674Y-137311D01*
X573733Y-137337D01*
X573800Y-137366D01*
X573866Y-137399D01*
X573940Y-137429D01*
X574018Y-137459D01*
X574177Y-137518D01*
X574347Y-137573D01*
X574351D01*
X574362Y-137577D01*
X574381Y-137581D01*
X574403Y-137588D01*
X574432Y-137595D01*
X574469Y-137603D01*
X574510Y-137614D01*
X574554Y-137621D01*
X574606Y-137633D01*
X574662Y-137644D01*
X574780Y-137662D01*
X574910Y-137681D01*
X575050Y-137692D01*
Y-138014D01*
X575047D01*
X575035D01*
X575021D01*
X574999Y-138010D01*
X574969D01*
X574932Y-138006D01*
X574891Y-138003D01*
X574847Y-137999D01*
X574795Y-137991D01*
X574743Y-137984D01*
X574680Y-137973D01*
X574617Y-137962D01*
X574551Y-137951D01*
X574477Y-137936D01*
X574325Y-137899D01*
X574321D01*
X574307Y-137895D01*
X574284Y-137888D01*
X574251Y-137877D01*
X574214Y-137866D01*
X574170Y-137851D01*
X574118Y-137836D01*
X574062Y-137814D01*
X574000Y-137792D01*
X573937Y-137769D01*
X573796Y-137714D01*
X573648Y-137647D01*
X573500Y-137573D01*
X573496Y-137570D01*
X573482Y-137562D01*
X573463Y-137551D01*
X573433Y-137536D01*
X573400Y-137518D01*
X573359Y-137492D01*
X573315Y-137466D01*
X573267Y-137436D01*
X573160Y-137366D01*
X573049Y-137292D01*
X572934Y-137207D01*
X572827Y-137118D01*
Y-138373D01*
X572523D01*
Y-136715D01*
X572771D01*
X572775Y-136719D01*
D02*
G37*
G36*
X575050Y-139016D02*
X574517Y-139353D01*
X574514D01*
X574506Y-139360D01*
X574495Y-139368D01*
X574480Y-139379D01*
X574440Y-139405D01*
X574388Y-139438D01*
X574333Y-139479D01*
X574273Y-139520D01*
X574218Y-139560D01*
X574166Y-139597D01*
X574162Y-139601D01*
X574148Y-139612D01*
X574125Y-139630D01*
X574099Y-139656D01*
X574044Y-139712D01*
X574018Y-139742D01*
X573996Y-139771D01*
X573992Y-139775D01*
X573988Y-139782D01*
X573981Y-139797D01*
X573970Y-139819D01*
X573959Y-139841D01*
X573948Y-139867D01*
X573929Y-139927D01*
Y-139930D01*
X573925Y-139938D01*
Y-139952D01*
X573922Y-139971D01*
X573918Y-139997D01*
Y-140026D01*
X573914Y-140067D01*
Y-140504D01*
X575050D01*
Y-140844D01*
X572490D01*
Y-139656D01*
X572494Y-139627D01*
Y-139594D01*
X572497Y-139516D01*
X572508Y-139434D01*
X572519Y-139346D01*
X572538Y-139264D01*
X572549Y-139224D01*
X572560Y-139190D01*
Y-139187D01*
X572564Y-139183D01*
X572575Y-139161D01*
X572590Y-139127D01*
X572616Y-139087D01*
X572649Y-139042D01*
X572693Y-138994D01*
X572745Y-138950D01*
X572804Y-138905D01*
X572808D01*
X572812Y-138902D01*
X572834Y-138887D01*
X572871Y-138872D01*
X572919Y-138850D01*
X572975Y-138831D01*
X573041Y-138813D01*
X573111Y-138802D01*
X573189Y-138798D01*
X573193D01*
X573200D01*
X573215D01*
X573234Y-138802D01*
X573259D01*
X573285Y-138805D01*
X573348Y-138820D01*
X573422Y-138842D01*
X573500Y-138872D01*
X573578Y-138916D01*
X573615Y-138946D01*
X573652Y-138976D01*
X573655Y-138979D01*
X573659Y-138983D01*
X573670Y-138994D01*
X573681Y-139009D01*
X573696Y-139027D01*
X573711Y-139050D01*
X573729Y-139079D01*
X573752Y-139109D01*
X573770Y-139146D01*
X573789Y-139187D01*
X573811Y-139231D01*
X573829Y-139279D01*
X573844Y-139334D01*
X573863Y-139390D01*
X573874Y-139453D01*
X573885Y-139520D01*
X573888Y-139512D01*
X573896Y-139497D01*
X573911Y-139475D01*
X573925Y-139445D01*
X573966Y-139379D01*
X573992Y-139346D01*
X574014Y-139316D01*
X574022Y-139309D01*
X574040Y-139290D01*
X574070Y-139260D01*
X574107Y-139224D01*
X574159Y-139183D01*
X574214Y-139135D01*
X574281Y-139087D01*
X574355Y-139035D01*
X575050Y-138594D01*
Y-139016D01*
D02*
G37*
G36*
X562827Y-104011D02*
X562853D01*
X562882Y-104014D01*
X562953Y-104029D01*
X563030Y-104048D01*
X563112Y-104077D01*
X563193Y-104118D01*
X563234Y-104144D01*
X563271Y-104174D01*
X563274Y-104177D01*
X563278Y-104181D01*
X563289Y-104192D01*
X563300Y-104203D01*
X563315Y-104222D01*
X563334Y-104244D01*
X563371Y-104296D01*
X563408Y-104362D01*
X563445Y-104444D01*
X563474Y-104536D01*
X563496Y-104643D01*
X563193Y-104669D01*
Y-104666D01*
X563189Y-104658D01*
Y-104651D01*
X563186Y-104636D01*
X563175Y-104595D01*
X563160Y-104551D01*
X563141Y-104499D01*
X563115Y-104447D01*
X563086Y-104399D01*
X563049Y-104358D01*
X563045Y-104355D01*
X563030Y-104344D01*
X563004Y-104329D01*
X562975Y-104314D01*
X562934Y-104296D01*
X562886Y-104281D01*
X562830Y-104270D01*
X562771Y-104266D01*
X562745D01*
X562719Y-104270D01*
X562686Y-104273D01*
X562645Y-104281D01*
X562605Y-104292D01*
X562560Y-104307D01*
X562520Y-104329D01*
X562516Y-104333D01*
X562501Y-104340D01*
X562479Y-104355D01*
X562457Y-104377D01*
X562427Y-104403D01*
X562398Y-104432D01*
X562368Y-104466D01*
X562338Y-104507D01*
X562335Y-104510D01*
X562327Y-104529D01*
X562313Y-104555D01*
X562298Y-104588D01*
X562279Y-104632D01*
X562261Y-104684D01*
X562242Y-104743D01*
X562224Y-104810D01*
Y-104814D01*
X562220Y-104817D01*
Y-104828D01*
X562216Y-104843D01*
X562209Y-104880D01*
X562198Y-104928D01*
X562190Y-104988D01*
X562183Y-105050D01*
X562179Y-105121D01*
X562176Y-105195D01*
Y-105198D01*
Y-105210D01*
Y-105228D01*
Y-105258D01*
X562179Y-105250D01*
X562194Y-105232D01*
X562216Y-105206D01*
X562242Y-105169D01*
X562279Y-105132D01*
X562324Y-105091D01*
X562375Y-105050D01*
X562435Y-105013D01*
X562442Y-105010D01*
X562464Y-104999D01*
X562498Y-104984D01*
X562538Y-104969D01*
X562594Y-104950D01*
X562653Y-104936D01*
X562719Y-104925D01*
X562790Y-104921D01*
X562819D01*
X562842Y-104925D01*
X562871Y-104928D01*
X562901Y-104932D01*
X562938Y-104939D01*
X562975Y-104950D01*
X563060Y-104976D01*
X563104Y-104995D01*
X563149Y-105017D01*
X563197Y-105043D01*
X563241Y-105076D01*
X563286Y-105110D01*
X563326Y-105150D01*
X563330Y-105154D01*
X563337Y-105161D01*
X563345Y-105173D01*
X563360Y-105191D01*
X563378Y-105217D01*
X563397Y-105243D01*
X563415Y-105276D01*
X563434Y-105313D01*
X563456Y-105354D01*
X563474Y-105398D01*
X563493Y-105450D01*
X563511Y-105502D01*
X563526Y-105561D01*
X563533Y-105624D01*
X563541Y-105687D01*
X563545Y-105757D01*
Y-105761D01*
Y-105776D01*
Y-105794D01*
X563541Y-105820D01*
X563537Y-105853D01*
X563533Y-105894D01*
X563526Y-105935D01*
X563515Y-105983D01*
X563489Y-106079D01*
X563471Y-106131D01*
X563448Y-106186D01*
X563422Y-106238D01*
X563389Y-106286D01*
X563356Y-106338D01*
X563315Y-106382D01*
X563311Y-106386D01*
X563304Y-106394D01*
X563293Y-106405D01*
X563274Y-106419D01*
X563252Y-106438D01*
X563223Y-106460D01*
X563193Y-106479D01*
X563156Y-106504D01*
X563119Y-106527D01*
X563075Y-106545D01*
X562975Y-106586D01*
X562923Y-106601D01*
X562864Y-106612D01*
X562805Y-106619D01*
X562742Y-106623D01*
X562716D01*
X562697Y-106619D01*
X562679D01*
X562653Y-106615D01*
X562590Y-106604D01*
X562520Y-106590D01*
X562442Y-106564D01*
X562364Y-106530D01*
X562287Y-106486D01*
X562283D01*
X562279Y-106479D01*
X562268Y-106471D01*
X562253Y-106460D01*
X562216Y-106430D01*
X562168Y-106390D01*
X562120Y-106334D01*
X562065Y-106268D01*
X562016Y-106190D01*
X561972Y-106101D01*
Y-106097D01*
X561968Y-106090D01*
X561961Y-106075D01*
X561954Y-106057D01*
X561946Y-106031D01*
X561935Y-105998D01*
X561928Y-105961D01*
X561917Y-105920D01*
X561905Y-105872D01*
X561894Y-105816D01*
X561887Y-105757D01*
X561880Y-105694D01*
X561872Y-105624D01*
X561865Y-105550D01*
X561861Y-105468D01*
Y-105383D01*
Y-105380D01*
Y-105361D01*
Y-105335D01*
Y-105302D01*
X561865Y-105261D01*
Y-105213D01*
X561868Y-105158D01*
X561876Y-105102D01*
X561887Y-104976D01*
X561905Y-104843D01*
X561931Y-104717D01*
X561950Y-104655D01*
X561968Y-104599D01*
Y-104595D01*
X561972Y-104588D01*
X561979Y-104573D01*
X561987Y-104551D01*
X561998Y-104529D01*
X562013Y-104499D01*
X562050Y-104436D01*
X562094Y-104366D01*
X562146Y-104292D01*
X562213Y-104222D01*
X562287Y-104159D01*
X562290D01*
X562298Y-104151D01*
X562309Y-104144D01*
X562324Y-104137D01*
X562346Y-104125D01*
X562368Y-104111D01*
X562398Y-104096D01*
X562427Y-104085D01*
X562498Y-104055D01*
X562583Y-104029D01*
X562675Y-104014D01*
X562779Y-104007D01*
X562808D01*
X562827Y-104011D01*
D02*
G37*
G36*
X565994Y-106612D02*
X564806D01*
X564777Y-106608D01*
X564743D01*
X564666Y-106604D01*
X564584Y-106593D01*
X564496Y-106582D01*
X564414Y-106564D01*
X564373Y-106553D01*
X564340Y-106542D01*
X564336D01*
X564333Y-106538D01*
X564311Y-106527D01*
X564277Y-106512D01*
X564236Y-106486D01*
X564192Y-106453D01*
X564144Y-106408D01*
X564100Y-106357D01*
X564055Y-106297D01*
Y-106294D01*
X564051Y-106290D01*
X564037Y-106268D01*
X564022Y-106231D01*
X564000Y-106183D01*
X563981Y-106127D01*
X563963Y-106061D01*
X563952Y-105990D01*
X563948Y-105912D01*
Y-105909D01*
Y-105901D01*
Y-105887D01*
X563952Y-105868D01*
Y-105842D01*
X563955Y-105816D01*
X563970Y-105753D01*
X563992Y-105679D01*
X564022Y-105602D01*
X564066Y-105524D01*
X564096Y-105487D01*
X564125Y-105450D01*
X564129Y-105446D01*
X564133Y-105443D01*
X564144Y-105431D01*
X564159Y-105420D01*
X564177Y-105406D01*
X564199Y-105391D01*
X564229Y-105372D01*
X564259Y-105350D01*
X564296Y-105332D01*
X564336Y-105313D01*
X564381Y-105291D01*
X564429Y-105272D01*
X564484Y-105258D01*
X564540Y-105239D01*
X564603Y-105228D01*
X564669Y-105217D01*
X564662Y-105213D01*
X564647Y-105206D01*
X564625Y-105191D01*
X564595Y-105176D01*
X564529Y-105136D01*
X564496Y-105110D01*
X564466Y-105087D01*
X564459Y-105080D01*
X564440Y-105061D01*
X564410Y-105032D01*
X564373Y-104995D01*
X564333Y-104943D01*
X564285Y-104888D01*
X564236Y-104821D01*
X564185Y-104747D01*
X563744Y-104051D01*
X564166D01*
X564503Y-104584D01*
Y-104588D01*
X564510Y-104595D01*
X564518Y-104606D01*
X564529Y-104621D01*
X564555Y-104662D01*
X564588Y-104714D01*
X564629Y-104769D01*
X564669Y-104828D01*
X564710Y-104884D01*
X564747Y-104936D01*
X564751Y-104939D01*
X564762Y-104954D01*
X564780Y-104976D01*
X564806Y-105002D01*
X564862Y-105058D01*
X564891Y-105084D01*
X564921Y-105106D01*
X564925Y-105110D01*
X564932Y-105113D01*
X564947Y-105121D01*
X564969Y-105132D01*
X564991Y-105143D01*
X565017Y-105154D01*
X565076Y-105173D01*
X565080D01*
X565088Y-105176D01*
X565102D01*
X565121Y-105180D01*
X565147Y-105184D01*
X565176D01*
X565217Y-105187D01*
X565654D01*
Y-104051D01*
X565994D01*
Y-106612D01*
D02*
G37*
G36*
X116472Y-264906D02*
X115284D01*
X115255Y-264902D01*
X115222D01*
X115144Y-264899D01*
X115062Y-264888D01*
X114974Y-264877D01*
X114892Y-264858D01*
X114851Y-264847D01*
X114818Y-264836D01*
X114815D01*
X114811Y-264832D01*
X114789Y-264821D01*
X114755Y-264806D01*
X114715Y-264780D01*
X114670Y-264747D01*
X114622Y-264703D01*
X114578Y-264651D01*
X114533Y-264592D01*
Y-264588D01*
X114530Y-264584D01*
X114515Y-264562D01*
X114500Y-264525D01*
X114478Y-264477D01*
X114459Y-264422D01*
X114441Y-264355D01*
X114430Y-264285D01*
X114426Y-264207D01*
Y-264203D01*
Y-264196D01*
Y-264181D01*
X114430Y-264162D01*
Y-264137D01*
X114433Y-264111D01*
X114448Y-264048D01*
X114471Y-263974D01*
X114500Y-263896D01*
X114544Y-263818D01*
X114574Y-263781D01*
X114604Y-263744D01*
X114607Y-263741D01*
X114611Y-263737D01*
X114622Y-263726D01*
X114637Y-263715D01*
X114655Y-263700D01*
X114678Y-263685D01*
X114707Y-263667D01*
X114737Y-263645D01*
X114774Y-263626D01*
X114815Y-263608D01*
X114859Y-263585D01*
X114907Y-263567D01*
X114963Y-263552D01*
X115018Y-263533D01*
X115081Y-263522D01*
X115148Y-263511D01*
X115140Y-263508D01*
X115125Y-263500D01*
X115103Y-263485D01*
X115074Y-263471D01*
X115007Y-263430D01*
X114974Y-263404D01*
X114944Y-263382D01*
X114937Y-263374D01*
X114918Y-263356D01*
X114889Y-263326D01*
X114851Y-263289D01*
X114811Y-263238D01*
X114763Y-263182D01*
X114715Y-263115D01*
X114663Y-263041D01*
X114223Y-262346D01*
X114644D01*
X114981Y-262879D01*
Y-262882D01*
X114988Y-262890D01*
X114996Y-262901D01*
X115007Y-262916D01*
X115033Y-262956D01*
X115066Y-263008D01*
X115107Y-263064D01*
X115148Y-263123D01*
X115188Y-263178D01*
X115225Y-263230D01*
X115229Y-263234D01*
X115240Y-263249D01*
X115259Y-263271D01*
X115284Y-263297D01*
X115340Y-263352D01*
X115370Y-263378D01*
X115399Y-263400D01*
X115403Y-263404D01*
X115410Y-263408D01*
X115425Y-263415D01*
X115447Y-263426D01*
X115470Y-263437D01*
X115495Y-263448D01*
X115554Y-263467D01*
X115558D01*
X115566Y-263471D01*
X115580D01*
X115599Y-263474D01*
X115625Y-263478D01*
X115654D01*
X115695Y-263482D01*
X116132D01*
Y-262346D01*
X116472D01*
Y-264906D01*
D02*
G37*
G36*
X114067Y-262350D02*
Y-262364D01*
Y-262386D01*
X114063Y-262416D01*
X114060Y-262449D01*
X114052Y-262486D01*
X114045Y-262523D01*
X114030Y-262564D01*
Y-262568D01*
X114026Y-262572D01*
X114019Y-262594D01*
X114004Y-262627D01*
X113982Y-262671D01*
X113952Y-262723D01*
X113916Y-262782D01*
X113875Y-262842D01*
X113823Y-262905D01*
Y-262908D01*
X113816Y-262912D01*
X113797Y-262934D01*
X113764Y-262967D01*
X113716Y-263016D01*
X113660Y-263071D01*
X113590Y-263138D01*
X113505Y-263212D01*
X113412Y-263289D01*
X113409Y-263293D01*
X113394Y-263304D01*
X113372Y-263323D01*
X113346Y-263345D01*
X113312Y-263374D01*
X113272Y-263408D01*
X113231Y-263445D01*
X113183Y-263485D01*
X113090Y-263574D01*
X112998Y-263663D01*
X112953Y-263707D01*
X112913Y-263752D01*
X112876Y-263792D01*
X112846Y-263833D01*
Y-263837D01*
X112839Y-263841D01*
X112831Y-263852D01*
X112824Y-263866D01*
X112798Y-263907D01*
X112768Y-263955D01*
X112743Y-264015D01*
X112717Y-264077D01*
X112702Y-264148D01*
X112695Y-264214D01*
Y-264218D01*
Y-264222D01*
X112698Y-264244D01*
X112702Y-264281D01*
X112713Y-264322D01*
X112728Y-264373D01*
X112754Y-264425D01*
X112787Y-264477D01*
X112831Y-264529D01*
X112839Y-264536D01*
X112857Y-264551D01*
X112883Y-264569D01*
X112924Y-264595D01*
X112976Y-264618D01*
X113035Y-264640D01*
X113105Y-264655D01*
X113183Y-264658D01*
X113205D01*
X113220Y-264655D01*
X113264Y-264651D01*
X113316Y-264640D01*
X113372Y-264625D01*
X113434Y-264599D01*
X113494Y-264566D01*
X113549Y-264521D01*
X113557Y-264514D01*
X113571Y-264495D01*
X113594Y-264466D01*
X113616Y-264422D01*
X113642Y-264370D01*
X113664Y-264303D01*
X113679Y-264229D01*
X113686Y-264144D01*
X114008Y-264177D01*
Y-264181D01*
X114004Y-264192D01*
Y-264211D01*
X114000Y-264236D01*
X113993Y-264266D01*
X113986Y-264299D01*
X113975Y-264340D01*
X113964Y-264381D01*
X113934Y-264470D01*
X113890Y-264558D01*
X113864Y-264603D01*
X113830Y-264647D01*
X113797Y-264688D01*
X113760Y-264725D01*
X113756Y-264729D01*
X113749Y-264732D01*
X113738Y-264743D01*
X113719Y-264755D01*
X113697Y-264769D01*
X113671Y-264784D01*
X113642Y-264803D01*
X113605Y-264821D01*
X113564Y-264840D01*
X113520Y-264858D01*
X113471Y-264873D01*
X113420Y-264888D01*
X113364Y-264899D01*
X113305Y-264910D01*
X113242Y-264914D01*
X113175Y-264917D01*
X113138D01*
X113113Y-264914D01*
X113083Y-264910D01*
X113046Y-264906D01*
X113005Y-264899D01*
X112965Y-264891D01*
X112868Y-264865D01*
X112772Y-264828D01*
X112724Y-264806D01*
X112676Y-264780D01*
X112631Y-264747D01*
X112591Y-264710D01*
X112587Y-264706D01*
X112580Y-264703D01*
X112572Y-264688D01*
X112557Y-264673D01*
X112539Y-264655D01*
X112521Y-264629D01*
X112502Y-264603D01*
X112480Y-264569D01*
X112443Y-264499D01*
X112406Y-264410D01*
X112391Y-264366D01*
X112384Y-264314D01*
X112376Y-264262D01*
X112373Y-264207D01*
Y-264199D01*
Y-264181D01*
X112376Y-264151D01*
X112380Y-264111D01*
X112387Y-264066D01*
X112402Y-264015D01*
X112417Y-263959D01*
X112439Y-263903D01*
X112443Y-263896D01*
X112450Y-263878D01*
X112465Y-263848D01*
X112487Y-263807D01*
X112517Y-263763D01*
X112554Y-263707D01*
X112598Y-263652D01*
X112650Y-263589D01*
X112657Y-263582D01*
X112676Y-263559D01*
X112695Y-263541D01*
X112713Y-263522D01*
X112735Y-263500D01*
X112765Y-263471D01*
X112794Y-263441D01*
X112831Y-263408D01*
X112868Y-263371D01*
X112913Y-263330D01*
X112961Y-263289D01*
X113013Y-263241D01*
X113072Y-263193D01*
X113131Y-263141D01*
X113135Y-263138D01*
X113142Y-263130D01*
X113157Y-263119D01*
X113175Y-263104D01*
X113198Y-263082D01*
X113224Y-263060D01*
X113283Y-263012D01*
X113346Y-262956D01*
X113405Y-262901D01*
X113457Y-262853D01*
X113479Y-262834D01*
X113497Y-262816D01*
X113501Y-262812D01*
X113512Y-262801D01*
X113527Y-262786D01*
X113546Y-262764D01*
X113564Y-262738D01*
X113586Y-262712D01*
X113630Y-262649D01*
X112369D01*
Y-262346D01*
X114067D01*
Y-262350D01*
D02*
G37*
G36*
X112076D02*
Y-262364D01*
Y-262386D01*
X112073Y-262416D01*
X112069Y-262449D01*
X112062Y-262486D01*
X112054Y-262523D01*
X112040Y-262564D01*
Y-262568D01*
X112036Y-262572D01*
X112028Y-262594D01*
X112014Y-262627D01*
X111992Y-262671D01*
X111962Y-262723D01*
X111925Y-262782D01*
X111884Y-262842D01*
X111832Y-262905D01*
Y-262908D01*
X111825Y-262912D01*
X111806Y-262934D01*
X111773Y-262967D01*
X111725Y-263016D01*
X111670Y-263071D01*
X111599Y-263138D01*
X111514Y-263212D01*
X111422Y-263289D01*
X111418Y-263293D01*
X111403Y-263304D01*
X111381Y-263323D01*
X111355Y-263345D01*
X111322Y-263374D01*
X111281Y-263408D01*
X111240Y-263445D01*
X111192Y-263485D01*
X111100Y-263574D01*
X111007Y-263663D01*
X110963Y-263707D01*
X110922Y-263752D01*
X110885Y-263792D01*
X110855Y-263833D01*
Y-263837D01*
X110848Y-263841D01*
X110841Y-263852D01*
X110833Y-263866D01*
X110807Y-263907D01*
X110778Y-263955D01*
X110752Y-264015D01*
X110726Y-264077D01*
X110711Y-264148D01*
X110704Y-264214D01*
Y-264218D01*
Y-264222D01*
X110707Y-264244D01*
X110711Y-264281D01*
X110722Y-264322D01*
X110737Y-264373D01*
X110763Y-264425D01*
X110796Y-264477D01*
X110841Y-264529D01*
X110848Y-264536D01*
X110867Y-264551D01*
X110893Y-264569D01*
X110933Y-264595D01*
X110985Y-264618D01*
X111044Y-264640D01*
X111115Y-264655D01*
X111192Y-264658D01*
X111214D01*
X111229Y-264655D01*
X111274Y-264651D01*
X111326Y-264640D01*
X111381Y-264625D01*
X111444Y-264599D01*
X111503Y-264566D01*
X111558Y-264521D01*
X111566Y-264514D01*
X111581Y-264495D01*
X111603Y-264466D01*
X111625Y-264422D01*
X111651Y-264370D01*
X111673Y-264303D01*
X111688Y-264229D01*
X111696Y-264144D01*
X112017Y-264177D01*
Y-264181D01*
X112014Y-264192D01*
Y-264211D01*
X112010Y-264236D01*
X112003Y-264266D01*
X111995Y-264299D01*
X111984Y-264340D01*
X111973Y-264381D01*
X111943Y-264470D01*
X111899Y-264558D01*
X111873Y-264603D01*
X111840Y-264647D01*
X111806Y-264688D01*
X111769Y-264725D01*
X111766Y-264729D01*
X111758Y-264732D01*
X111747Y-264743D01*
X111729Y-264755D01*
X111706Y-264769D01*
X111681Y-264784D01*
X111651Y-264803D01*
X111614Y-264821D01*
X111573Y-264840D01*
X111529Y-264858D01*
X111481Y-264873D01*
X111429Y-264888D01*
X111374Y-264899D01*
X111314Y-264910D01*
X111251Y-264914D01*
X111185Y-264917D01*
X111148D01*
X111122Y-264914D01*
X111092Y-264910D01*
X111055Y-264906D01*
X111015Y-264899D01*
X110974Y-264891D01*
X110878Y-264865D01*
X110782Y-264828D01*
X110733Y-264806D01*
X110685Y-264780D01*
X110641Y-264747D01*
X110600Y-264710D01*
X110597Y-264706D01*
X110589Y-264703D01*
X110582Y-264688D01*
X110567Y-264673D01*
X110548Y-264655D01*
X110530Y-264629D01*
X110511Y-264603D01*
X110489Y-264569D01*
X110452Y-264499D01*
X110415Y-264410D01*
X110400Y-264366D01*
X110393Y-264314D01*
X110386Y-264262D01*
X110382Y-264207D01*
Y-264199D01*
Y-264181D01*
X110386Y-264151D01*
X110389Y-264111D01*
X110397Y-264066D01*
X110412Y-264015D01*
X110426Y-263959D01*
X110449Y-263903D01*
X110452Y-263896D01*
X110460Y-263878D01*
X110475Y-263848D01*
X110497Y-263807D01*
X110526Y-263763D01*
X110563Y-263707D01*
X110608Y-263652D01*
X110659Y-263589D01*
X110667Y-263582D01*
X110685Y-263559D01*
X110704Y-263541D01*
X110722Y-263522D01*
X110745Y-263500D01*
X110774Y-263471D01*
X110804Y-263441D01*
X110841Y-263408D01*
X110878Y-263371D01*
X110922Y-263330D01*
X110970Y-263289D01*
X111022Y-263241D01*
X111081Y-263193D01*
X111141Y-263141D01*
X111144Y-263138D01*
X111152Y-263130D01*
X111166Y-263119D01*
X111185Y-263104D01*
X111207Y-263082D01*
X111233Y-263060D01*
X111292Y-263012D01*
X111355Y-262956D01*
X111414Y-262901D01*
X111466Y-262853D01*
X111488Y-262834D01*
X111507Y-262816D01*
X111510Y-262812D01*
X111522Y-262801D01*
X111536Y-262786D01*
X111555Y-262764D01*
X111573Y-262738D01*
X111596Y-262712D01*
X111640Y-262649D01*
X110378D01*
Y-262346D01*
X112076D01*
Y-262350D01*
D02*
G37*
%LPC*%
G36*
X554130Y-232048D02*
X553368D01*
X553324Y-232052D01*
X553272Y-232055D01*
X553213Y-232059D01*
X553153Y-232066D01*
X553094Y-232078D01*
X553042Y-232092D01*
X553035Y-232096D01*
X553020Y-232103D01*
X552998Y-232115D01*
X552968Y-232129D01*
X552935Y-232152D01*
X552902Y-232177D01*
X552869Y-232211D01*
X552843Y-232248D01*
X552839Y-232252D01*
X552832Y-232266D01*
X552820Y-232289D01*
X552806Y-232318D01*
X552794Y-232351D01*
X552783Y-232388D01*
X552776Y-232433D01*
X552772Y-232477D01*
Y-232481D01*
Y-232485D01*
X552776Y-232507D01*
X552780Y-232540D01*
X552787Y-232585D01*
X552806Y-232629D01*
X552828Y-232681D01*
X552861Y-232729D01*
X552906Y-232777D01*
X552913Y-232781D01*
X552931Y-232795D01*
X552961Y-232814D01*
X553009Y-232836D01*
X553064Y-232858D01*
X553139Y-232877D01*
X553224Y-232892D01*
X553324Y-232895D01*
X554130D01*
Y-232048D01*
D02*
G37*
G36*
X549613Y-239840D02*
X549594D01*
X549579Y-239844D01*
X549543Y-239847D01*
X549494Y-239858D01*
X549443Y-239881D01*
X549383Y-239907D01*
X549324Y-239947D01*
X549295Y-239969D01*
X549269Y-239999D01*
Y-240003D01*
X549261Y-240006D01*
X549247Y-240029D01*
X549224Y-240066D01*
X549195Y-240114D01*
X549169Y-240177D01*
X549147Y-240251D01*
X549132Y-240336D01*
X549124Y-240436D01*
Y-240439D01*
Y-240447D01*
Y-240461D01*
X549128Y-240480D01*
Y-240502D01*
X549132Y-240528D01*
X549143Y-240587D01*
X549158Y-240654D01*
X549184Y-240724D01*
X549221Y-240791D01*
X549269Y-240854D01*
X549276Y-240861D01*
X549295Y-240880D01*
X549324Y-240902D01*
X549365Y-240931D01*
X549417Y-240961D01*
X549476Y-240983D01*
X549546Y-241002D01*
X549624Y-241009D01*
X549646D01*
X549661Y-241005D01*
X549698Y-241002D01*
X549750Y-240991D01*
X549805Y-240972D01*
X549868Y-240943D01*
X549927Y-240905D01*
X549987Y-240854D01*
X549994Y-240846D01*
X550009Y-240828D01*
X550035Y-240794D01*
X550061Y-240746D01*
X550086Y-240691D01*
X550112Y-240621D01*
X550127Y-240543D01*
X550135Y-240454D01*
Y-240447D01*
Y-240428D01*
X550131Y-240395D01*
X550127Y-240354D01*
X550120Y-240306D01*
X550105Y-240254D01*
X550090Y-240199D01*
X550068Y-240143D01*
X550064Y-240136D01*
X550053Y-240117D01*
X550038Y-240091D01*
X550016Y-240058D01*
X549990Y-240025D01*
X549957Y-239984D01*
X549920Y-239951D01*
X549875Y-239918D01*
X549868Y-239914D01*
X549853Y-239907D01*
X549827Y-239892D01*
X549794Y-239881D01*
X549757Y-239866D01*
X549713Y-239851D01*
X549665Y-239844D01*
X549613Y-239840D01*
D02*
G37*
G36*
X610541Y-242043D02*
Y-242849D01*
X611689D01*
X610541Y-242043D01*
D02*
G37*
G36*
X582589Y-228769D02*
X582585D01*
X582578D01*
X582563D01*
X582544Y-228773D01*
X582522D01*
X582496Y-228777D01*
X582437Y-228788D01*
X582370Y-228802D01*
X582300Y-228828D01*
X582233Y-228865D01*
X582171Y-228913D01*
X582163Y-228921D01*
X582145Y-228939D01*
X582123Y-228969D01*
X582093Y-229010D01*
X582063Y-229061D01*
X582041Y-229121D01*
X582023Y-229191D01*
X582015Y-229269D01*
Y-229291D01*
X582019Y-229306D01*
X582023Y-229343D01*
X582034Y-229394D01*
X582052Y-229450D01*
X582082Y-229513D01*
X582119Y-229572D01*
X582171Y-229631D01*
X582178Y-229639D01*
X582197Y-229653D01*
X582230Y-229679D01*
X582278Y-229705D01*
X582333Y-229731D01*
X582404Y-229757D01*
X582481Y-229772D01*
X582570Y-229779D01*
X582578D01*
X582596D01*
X582629Y-229776D01*
X582670Y-229772D01*
X582718Y-229764D01*
X582770Y-229750D01*
X582826Y-229735D01*
X582881Y-229713D01*
X582888Y-229709D01*
X582907Y-229698D01*
X582933Y-229683D01*
X582966Y-229661D01*
X582999Y-229635D01*
X583040Y-229602D01*
X583073Y-229565D01*
X583107Y-229520D01*
X583110Y-229513D01*
X583118Y-229498D01*
X583133Y-229472D01*
X583144Y-229439D01*
X583158Y-229402D01*
X583173Y-229357D01*
X583181Y-229309D01*
X583184Y-229257D01*
Y-229239D01*
X583181Y-229224D01*
X583177Y-229187D01*
X583166Y-229139D01*
X583144Y-229087D01*
X583118Y-229028D01*
X583077Y-228969D01*
X583055Y-228939D01*
X583025Y-228913D01*
X583022D01*
X583018Y-228906D01*
X582996Y-228891D01*
X582959Y-228869D01*
X582911Y-228839D01*
X582848Y-228814D01*
X582774Y-228791D01*
X582689Y-228777D01*
X582589Y-228769D01*
D02*
G37*
G36*
X581542Y-230878D02*
X581538D01*
X581534D01*
X581512Y-230882D01*
X581479Y-230886D01*
X581434Y-230893D01*
X581390Y-230911D01*
X581338Y-230934D01*
X581290Y-230967D01*
X581242Y-231011D01*
X581238Y-231019D01*
X581223Y-231037D01*
X581205Y-231067D01*
X581183Y-231115D01*
X581160Y-231170D01*
X581142Y-231244D01*
X581127Y-231329D01*
X581123Y-231429D01*
Y-232236D01*
X581971D01*
Y-231474D01*
X581967Y-231429D01*
X581963Y-231378D01*
X581960Y-231318D01*
X581952Y-231259D01*
X581941Y-231200D01*
X581926Y-231148D01*
X581923Y-231141D01*
X581915Y-231126D01*
X581904Y-231104D01*
X581889Y-231074D01*
X581867Y-231041D01*
X581841Y-231008D01*
X581808Y-230974D01*
X581771Y-230948D01*
X581767Y-230945D01*
X581752Y-230937D01*
X581730Y-230926D01*
X581701Y-230911D01*
X581667Y-230900D01*
X581630Y-230889D01*
X581586Y-230882D01*
X581542Y-230878D01*
D02*
G37*
G36*
X582796Y-218509D02*
X581649D01*
X582796Y-219315D01*
Y-218509D01*
D02*
G37*
G36*
X581842Y-220266D02*
X581838D01*
X581834D01*
X581812Y-220270D01*
X581779Y-220274D01*
X581734Y-220281D01*
X581690Y-220300D01*
X581638Y-220322D01*
X581590Y-220355D01*
X581542Y-220399D01*
X581538Y-220407D01*
X581524Y-220425D01*
X581505Y-220455D01*
X581483Y-220503D01*
X581461Y-220559D01*
X581442Y-220633D01*
X581427Y-220718D01*
X581424Y-220818D01*
Y-221624D01*
X582271D01*
Y-220862D01*
X582267Y-220818D01*
X582264Y-220766D01*
X582260Y-220707D01*
X582252Y-220647D01*
X582241Y-220588D01*
X582227Y-220536D01*
X582223Y-220529D01*
X582215Y-220514D01*
X582204Y-220492D01*
X582190Y-220462D01*
X582167Y-220429D01*
X582141Y-220396D01*
X582108Y-220362D01*
X582071Y-220337D01*
X582067Y-220333D01*
X582053Y-220325D01*
X582030Y-220314D01*
X582001Y-220300D01*
X581967Y-220288D01*
X581930Y-220277D01*
X581886Y-220270D01*
X581842Y-220266D01*
D02*
G37*
G36*
X575200Y-207054D02*
X574438D01*
X574394Y-207058D01*
X574342Y-207062D01*
X574282Y-207066D01*
X574223Y-207073D01*
X574164Y-207084D01*
X574112Y-207099D01*
X574105Y-207102D01*
X574090Y-207110D01*
X574068Y-207121D01*
X574038Y-207136D01*
X574005Y-207158D01*
X573972Y-207184D01*
X573938Y-207217D01*
X573912Y-207254D01*
X573909Y-207258D01*
X573901Y-207273D01*
X573890Y-207295D01*
X573876Y-207325D01*
X573864Y-207358D01*
X573853Y-207395D01*
X573846Y-207439D01*
X573842Y-207484D01*
Y-207487D01*
Y-207491D01*
X573846Y-207513D01*
X573849Y-207546D01*
X573857Y-207591D01*
X573876Y-207635D01*
X573898Y-207687D01*
X573931Y-207735D01*
X573975Y-207783D01*
X573983Y-207787D01*
X574001Y-207802D01*
X574031Y-207820D01*
X574079Y-207842D01*
X574134Y-207865D01*
X574208Y-207883D01*
X574294Y-207898D01*
X574394Y-207902D01*
X575200D01*
Y-207054D01*
D02*
G37*
G36*
X572251Y-205841D02*
X572229D01*
X572214Y-205844D01*
X572170Y-205848D01*
X572118Y-205859D01*
X572059Y-205878D01*
X571996Y-205900D01*
X571937Y-205937D01*
X571877Y-205985D01*
X571870Y-205993D01*
X571855Y-206011D01*
X571829Y-206044D01*
X571803Y-206085D01*
X571777Y-206137D01*
X571752Y-206200D01*
X571737Y-206274D01*
X571729Y-206351D01*
Y-206355D01*
Y-206363D01*
Y-206374D01*
X571733Y-206388D01*
X571737Y-206429D01*
X571748Y-206485D01*
X571766Y-206540D01*
X571792Y-206603D01*
X571829Y-206666D01*
X571881Y-206725D01*
X571889Y-206733D01*
X571907Y-206747D01*
X571940Y-206773D01*
X571985Y-206803D01*
X572040Y-206829D01*
X572107Y-206855D01*
X572181Y-206869D01*
X572262Y-206877D01*
X572285D01*
X572299Y-206873D01*
X572340Y-206869D01*
X572392Y-206858D01*
X572451Y-206840D01*
X572510Y-206814D01*
X572573Y-206777D01*
X572628Y-206729D01*
X572636Y-206721D01*
X572651Y-206703D01*
X572673Y-206670D01*
X572699Y-206629D01*
X572728Y-206573D01*
X572751Y-206510D01*
X572765Y-206440D01*
X572773Y-206363D01*
Y-206355D01*
Y-206340D01*
X572769Y-206314D01*
X572765Y-206281D01*
X572758Y-206240D01*
X572747Y-206196D01*
X572732Y-206152D01*
X572714Y-206103D01*
X572710Y-206100D01*
X572703Y-206081D01*
X572688Y-206059D01*
X572666Y-206033D01*
X572640Y-206000D01*
X572606Y-205967D01*
X572569Y-205937D01*
X572525Y-205907D01*
X572518Y-205904D01*
X572503Y-205896D01*
X572477Y-205885D01*
X572443Y-205874D01*
X572403Y-205863D01*
X572355Y-205852D01*
X572303Y-205844D01*
X572251Y-205841D01*
D02*
G37*
G36*
Y-207132D02*
X572244D01*
X572222Y-207136D01*
X572188Y-207139D01*
X572144Y-207147D01*
X572096Y-207162D01*
X572048Y-207180D01*
X571996Y-207210D01*
X571951Y-207247D01*
X571948Y-207250D01*
X571933Y-207269D01*
X571914Y-207291D01*
X571892Y-207325D01*
X571870Y-207365D01*
X571852Y-207413D01*
X571837Y-207469D01*
X571833Y-207528D01*
Y-207532D01*
Y-207535D01*
Y-207558D01*
X571840Y-207591D01*
X571848Y-207632D01*
X571863Y-207676D01*
X571885Y-207724D01*
X571914Y-207772D01*
X571955Y-207820D01*
X571959Y-207824D01*
X571977Y-207839D01*
X572003Y-207857D01*
X572037Y-207879D01*
X572081Y-207902D01*
X572129Y-207920D01*
X572188Y-207935D01*
X572251Y-207939D01*
X572281D01*
X572314Y-207931D01*
X572358Y-207924D01*
X572406Y-207909D01*
X572458Y-207891D01*
X572507Y-207861D01*
X572555Y-207820D01*
X572558Y-207817D01*
X572573Y-207802D01*
X572592Y-207776D01*
X572610Y-207743D01*
X572632Y-207702D01*
X572651Y-207654D01*
X572666Y-207602D01*
X572669Y-207543D01*
Y-207539D01*
Y-207535D01*
X572666Y-207513D01*
X572662Y-207480D01*
X572654Y-207439D01*
X572640Y-207391D01*
X572621Y-207343D01*
X572592Y-207291D01*
X572555Y-207247D01*
X572551Y-207243D01*
X572532Y-207228D01*
X572507Y-207210D01*
X572473Y-207191D01*
X572429Y-207169D01*
X572377Y-207151D01*
X572318Y-207136D01*
X572251Y-207132D01*
D02*
G37*
G36*
X566867Y-254136D02*
X566061Y-255283D01*
X566867D01*
Y-254136D01*
D02*
G37*
G36*
X656368Y-175578D02*
X656365D01*
X656361D01*
X656339D01*
X656306Y-175585D01*
X656265Y-175593D01*
X656220Y-175608D01*
X656172Y-175630D01*
X656124Y-175660D01*
X656076Y-175700D01*
X656072Y-175704D01*
X656058Y-175722D01*
X656039Y-175748D01*
X656017Y-175782D01*
X655995Y-175826D01*
X655976Y-175874D01*
X655961Y-175933D01*
X655958Y-175996D01*
Y-176026D01*
X655965Y-176059D01*
X655972Y-176103D01*
X655987Y-176152D01*
X656006Y-176203D01*
X656035Y-176251D01*
X656076Y-176300D01*
X656080Y-176303D01*
X656095Y-176318D01*
X656120Y-176337D01*
X656154Y-176355D01*
X656194Y-176377D01*
X656243Y-176396D01*
X656294Y-176411D01*
X656354Y-176414D01*
X656357D01*
X656361D01*
X656383Y-176411D01*
X656417Y-176407D01*
X656457Y-176400D01*
X656505Y-176385D01*
X656553Y-176366D01*
X656605Y-176337D01*
X656650Y-176300D01*
X656653Y-176296D01*
X656668Y-176277D01*
X656687Y-176251D01*
X656705Y-176218D01*
X656727Y-176174D01*
X656746Y-176122D01*
X656761Y-176063D01*
X656764Y-175996D01*
Y-175989D01*
X656761Y-175967D01*
X656757Y-175933D01*
X656749Y-175889D01*
X656735Y-175841D01*
X656716Y-175793D01*
X656687Y-175741D01*
X656650Y-175697D01*
X656646Y-175693D01*
X656627Y-175678D01*
X656605Y-175660D01*
X656572Y-175637D01*
X656531Y-175615D01*
X656483Y-175597D01*
X656428Y-175582D01*
X656368Y-175578D01*
D02*
G37*
G36*
X657545Y-175475D02*
X657541D01*
X657534D01*
X657523D01*
X657508Y-175478D01*
X657467Y-175482D01*
X657412Y-175493D01*
X657356Y-175512D01*
X657293Y-175537D01*
X657231Y-175574D01*
X657171Y-175626D01*
X657164Y-175634D01*
X657149Y-175652D01*
X657123Y-175685D01*
X657094Y-175730D01*
X657068Y-175785D01*
X657042Y-175852D01*
X657027Y-175926D01*
X657020Y-176007D01*
Y-176030D01*
X657023Y-176044D01*
X657027Y-176085D01*
X657038Y-176137D01*
X657057Y-176196D01*
X657083Y-176255D01*
X657120Y-176318D01*
X657168Y-176374D01*
X657175Y-176381D01*
X657194Y-176396D01*
X657227Y-176418D01*
X657268Y-176444D01*
X657323Y-176473D01*
X657386Y-176496D01*
X657456Y-176511D01*
X657534Y-176518D01*
X657541D01*
X657556D01*
X657582Y-176514D01*
X657615Y-176511D01*
X657656Y-176503D01*
X657700Y-176492D01*
X657745Y-176477D01*
X657793Y-176459D01*
X657797Y-176455D01*
X657815Y-176448D01*
X657837Y-176433D01*
X657863Y-176411D01*
X657897Y-176385D01*
X657930Y-176351D01*
X657959Y-176314D01*
X657989Y-176270D01*
X657993Y-176263D01*
X658000Y-176248D01*
X658011Y-176222D01*
X658022Y-176189D01*
X658033Y-176148D01*
X658044Y-176100D01*
X658052Y-176048D01*
X658056Y-175996D01*
Y-175974D01*
X658052Y-175959D01*
X658048Y-175915D01*
X658037Y-175863D01*
X658019Y-175804D01*
X657996Y-175741D01*
X657959Y-175682D01*
X657911Y-175622D01*
X657904Y-175615D01*
X657885Y-175600D01*
X657852Y-175574D01*
X657811Y-175549D01*
X657760Y-175523D01*
X657697Y-175497D01*
X657623Y-175482D01*
X657545Y-175475D01*
D02*
G37*
G36*
X518484Y-330739D02*
X517892D01*
Y-332693D01*
X518499D01*
X518524Y-332689D01*
X518580Y-332685D01*
X518643Y-332681D01*
X518709Y-332674D01*
X518776Y-332663D01*
X518831Y-332648D01*
X518839Y-332644D01*
X518857Y-332641D01*
X518883Y-332630D01*
X518917Y-332615D01*
X518954Y-332593D01*
X518991Y-332570D01*
X519028Y-332544D01*
X519065Y-332515D01*
X519068Y-332507D01*
X519083Y-332493D01*
X519105Y-332467D01*
X519131Y-332430D01*
X519161Y-332382D01*
X519194Y-332326D01*
X519224Y-332263D01*
X519250Y-332193D01*
Y-332189D01*
X519253Y-332182D01*
X519257Y-332171D01*
X519261Y-332156D01*
X519264Y-332137D01*
X519272Y-332112D01*
X519279Y-332086D01*
X519287Y-332056D01*
X519298Y-331982D01*
X519309Y-331897D01*
X519316Y-331801D01*
X519320Y-331697D01*
Y-331694D01*
Y-331679D01*
Y-331660D01*
X519316Y-331631D01*
Y-331597D01*
X519312Y-331560D01*
X519309Y-331516D01*
X519305Y-331471D01*
X519287Y-331372D01*
X519264Y-331268D01*
X519231Y-331172D01*
X519209Y-331124D01*
X519187Y-331083D01*
Y-331079D01*
X519179Y-331072D01*
X519172Y-331061D01*
X519165Y-331046D01*
X519135Y-331009D01*
X519098Y-330965D01*
X519050Y-330917D01*
X518994Y-330868D01*
X518931Y-330828D01*
X518865Y-330794D01*
X518857Y-330791D01*
X518839Y-330787D01*
X518806Y-330776D01*
X518757Y-330765D01*
X518698Y-330757D01*
X518624Y-330746D01*
X518580Y-330743D01*
X518532D01*
X518484Y-330739D01*
D02*
G37*
G36*
X520774Y-347759D02*
X520751D01*
X520737Y-347763D01*
X520700Y-347767D01*
X520648Y-347778D01*
X520592Y-347796D01*
X520529Y-347826D01*
X520470Y-347863D01*
X520411Y-347915D01*
X520404Y-347922D01*
X520389Y-347941D01*
X520363Y-347974D01*
X520337Y-348022D01*
X520311Y-348078D01*
X520285Y-348148D01*
X520270Y-348226D01*
X520263Y-348314D01*
Y-348322D01*
Y-348340D01*
X520267Y-348374D01*
X520270Y-348414D01*
X520278Y-348462D01*
X520293Y-348514D01*
X520307Y-348570D01*
X520330Y-348625D01*
X520333Y-348633D01*
X520344Y-348651D01*
X520359Y-348677D01*
X520381Y-348710D01*
X520407Y-348744D01*
X520441Y-348784D01*
X520478Y-348818D01*
X520522Y-348851D01*
X520529Y-348855D01*
X520544Y-348862D01*
X520570Y-348877D01*
X520603Y-348888D01*
X520640Y-348903D01*
X520685Y-348918D01*
X520733Y-348925D01*
X520785Y-348929D01*
X520803D01*
X520818Y-348925D01*
X520855Y-348921D01*
X520903Y-348910D01*
X520955Y-348888D01*
X521014Y-348862D01*
X521073Y-348821D01*
X521103Y-348799D01*
X521129Y-348769D01*
Y-348766D01*
X521136Y-348762D01*
X521151Y-348740D01*
X521173Y-348703D01*
X521203Y-348655D01*
X521229Y-348592D01*
X521251Y-348518D01*
X521266Y-348433D01*
X521273Y-348333D01*
Y-348329D01*
Y-348322D01*
Y-348307D01*
X521269Y-348288D01*
Y-348266D01*
X521266Y-348240D01*
X521255Y-348181D01*
X521240Y-348115D01*
X521214Y-348044D01*
X521177Y-347978D01*
X521129Y-347915D01*
X521122Y-347907D01*
X521103Y-347889D01*
X521073Y-347867D01*
X521033Y-347837D01*
X520981Y-347808D01*
X520922Y-347785D01*
X520851Y-347767D01*
X520774Y-347759D01*
D02*
G37*
G36*
X518395Y-346886D02*
X517802D01*
Y-348840D01*
X518409D01*
X518435Y-348836D01*
X518491Y-348832D01*
X518554Y-348829D01*
X518620Y-348821D01*
X518687Y-348810D01*
X518742Y-348795D01*
X518750Y-348792D01*
X518768Y-348788D01*
X518794Y-348777D01*
X518827Y-348762D01*
X518864Y-348740D01*
X518901Y-348718D01*
X518938Y-348692D01*
X518975Y-348662D01*
X518979Y-348655D01*
X518994Y-348640D01*
X519016Y-348614D01*
X519042Y-348577D01*
X519072Y-348529D01*
X519105Y-348474D01*
X519135Y-348411D01*
X519161Y-348340D01*
Y-348337D01*
X519164Y-348329D01*
X519168Y-348318D01*
X519172Y-348303D01*
X519175Y-348285D01*
X519183Y-348259D01*
X519190Y-348233D01*
X519198Y-348203D01*
X519209Y-348129D01*
X519220Y-348044D01*
X519227Y-347948D01*
X519231Y-347845D01*
Y-347841D01*
Y-347826D01*
Y-347808D01*
X519227Y-347778D01*
Y-347745D01*
X519223Y-347708D01*
X519220Y-347663D01*
X519216Y-347619D01*
X519198Y-347519D01*
X519175Y-347415D01*
X519142Y-347319D01*
X519120Y-347271D01*
X519098Y-347230D01*
Y-347227D01*
X519090Y-347219D01*
X519083Y-347208D01*
X519075Y-347193D01*
X519046Y-347156D01*
X519009Y-347112D01*
X518961Y-347064D01*
X518905Y-347016D01*
X518842Y-346975D01*
X518776Y-346942D01*
X518768Y-346938D01*
X518750Y-346934D01*
X518716Y-346923D01*
X518668Y-346912D01*
X518609Y-346905D01*
X518535Y-346894D01*
X518491Y-346890D01*
X518443D01*
X518395Y-346886D01*
D02*
G37*
G36*
X638001Y-323075D02*
X636048D01*
Y-323682D01*
X636051Y-323708D01*
X636055Y-323763D01*
X636059Y-323826D01*
X636066Y-323893D01*
X636077Y-323960D01*
X636092Y-324015D01*
X636096Y-324023D01*
X636099Y-324041D01*
X636111Y-324067D01*
X636125Y-324100D01*
X636148Y-324137D01*
X636170Y-324174D01*
X636196Y-324211D01*
X636225Y-324248D01*
X636233Y-324252D01*
X636247Y-324267D01*
X636273Y-324289D01*
X636310Y-324315D01*
X636358Y-324344D01*
X636414Y-324378D01*
X636477Y-324407D01*
X636547Y-324433D01*
X636551D01*
X636558Y-324437D01*
X636569Y-324441D01*
X636584Y-324444D01*
X636603Y-324448D01*
X636629Y-324455D01*
X636655Y-324463D01*
X636684Y-324470D01*
X636758Y-324481D01*
X636843Y-324492D01*
X636939Y-324500D01*
X637043Y-324503D01*
X637047D01*
X637062D01*
X637080D01*
X637110Y-324500D01*
X637143D01*
X637180Y-324496D01*
X637224Y-324492D01*
X637269Y-324489D01*
X637369Y-324470D01*
X637472Y-324448D01*
X637568Y-324415D01*
X637616Y-324393D01*
X637657Y-324370D01*
X637661D01*
X637668Y-324363D01*
X637679Y-324356D01*
X637694Y-324348D01*
X637731Y-324319D01*
X637776Y-324282D01*
X637824Y-324233D01*
X637872Y-324178D01*
X637913Y-324115D01*
X637946Y-324048D01*
X637950Y-324041D01*
X637953Y-324023D01*
X637964Y-323989D01*
X637975Y-323941D01*
X637983Y-323882D01*
X637994Y-323808D01*
X637998Y-323763D01*
Y-323715D01*
X638001Y-323667D01*
Y-323075D01*
D02*
G37*
G36*
X637661Y-325610D02*
X637657D01*
X637653D01*
X637631Y-325613D01*
X637598Y-325617D01*
X637557Y-325625D01*
X637509Y-325639D01*
X637461Y-325658D01*
X637409Y-325688D01*
X637365Y-325725D01*
X637361Y-325728D01*
X637346Y-325747D01*
X637328Y-325773D01*
X637309Y-325806D01*
X637287Y-325850D01*
X637269Y-325902D01*
X637254Y-325961D01*
X637250Y-326028D01*
Y-326035D01*
X637254Y-326058D01*
X637258Y-326091D01*
X637265Y-326135D01*
X637280Y-326183D01*
X637298Y-326231D01*
X637328Y-326283D01*
X637365Y-326328D01*
X637369Y-326331D01*
X637387Y-326346D01*
X637409Y-326365D01*
X637443Y-326387D01*
X637483Y-326409D01*
X637531Y-326428D01*
X637587Y-326442D01*
X637646Y-326446D01*
X637650D01*
X637653D01*
X637676D01*
X637709Y-326439D01*
X637750Y-326431D01*
X637794Y-326416D01*
X637842Y-326394D01*
X637890Y-326365D01*
X637938Y-326324D01*
X637942Y-326320D01*
X637957Y-326302D01*
X637975Y-326276D01*
X637998Y-326242D01*
X638020Y-326198D01*
X638038Y-326150D01*
X638053Y-326091D01*
X638057Y-326028D01*
Y-325998D01*
X638049Y-325965D01*
X638042Y-325921D01*
X638027Y-325872D01*
X638009Y-325821D01*
X637979Y-325773D01*
X637938Y-325725D01*
X637935Y-325721D01*
X637920Y-325706D01*
X637894Y-325688D01*
X637861Y-325669D01*
X637820Y-325647D01*
X637772Y-325628D01*
X637720Y-325613D01*
X637661Y-325610D01*
D02*
G37*
G36*
X636481Y-325506D02*
X636473D01*
X636458D01*
X636433Y-325510D01*
X636399Y-325514D01*
X636358Y-325521D01*
X636314Y-325532D01*
X636270Y-325547D01*
X636222Y-325565D01*
X636218Y-325569D01*
X636199Y-325576D01*
X636177Y-325591D01*
X636151Y-325613D01*
X636118Y-325639D01*
X636085Y-325673D01*
X636055Y-325710D01*
X636025Y-325754D01*
X636022Y-325762D01*
X636014Y-325776D01*
X636003Y-325802D01*
X635992Y-325835D01*
X635981Y-325876D01*
X635970Y-325924D01*
X635963Y-325976D01*
X635959Y-326028D01*
Y-326050D01*
X635963Y-326065D01*
X635966Y-326109D01*
X635977Y-326161D01*
X635996Y-326220D01*
X636018Y-326283D01*
X636055Y-326342D01*
X636103Y-326402D01*
X636111Y-326409D01*
X636129Y-326424D01*
X636162Y-326450D01*
X636203Y-326476D01*
X636255Y-326501D01*
X636318Y-326527D01*
X636392Y-326542D01*
X636470Y-326550D01*
X636473D01*
X636481D01*
X636492D01*
X636507Y-326546D01*
X636547Y-326542D01*
X636603Y-326531D01*
X636658Y-326513D01*
X636721Y-326487D01*
X636784Y-326450D01*
X636843Y-326398D01*
X636851Y-326391D01*
X636865Y-326372D01*
X636891Y-326339D01*
X636921Y-326294D01*
X636947Y-326239D01*
X636973Y-326172D01*
X636987Y-326098D01*
X636995Y-326017D01*
Y-325995D01*
X636991Y-325980D01*
X636987Y-325939D01*
X636976Y-325887D01*
X636958Y-325828D01*
X636932Y-325769D01*
X636895Y-325706D01*
X636847Y-325651D01*
X636839Y-325643D01*
X636821Y-325628D01*
X636788Y-325606D01*
X636747Y-325580D01*
X636692Y-325551D01*
X636629Y-325528D01*
X636558Y-325514D01*
X636481Y-325506D01*
D02*
G37*
G36*
X656685Y-323176D02*
X654732D01*
Y-323782D01*
X654736Y-323808D01*
X654739Y-323864D01*
X654743Y-323927D01*
X654750Y-323993D01*
X654761Y-324060D01*
X654776Y-324115D01*
X654780Y-324123D01*
X654784Y-324141D01*
X654795Y-324167D01*
X654810Y-324201D01*
X654832Y-324237D01*
X654854Y-324274D01*
X654880Y-324311D01*
X654909Y-324348D01*
X654917Y-324352D01*
X654932Y-324367D01*
X654957Y-324389D01*
X654994Y-324415D01*
X655043Y-324445D01*
X655098Y-324478D01*
X655161Y-324507D01*
X655231Y-324533D01*
X655235D01*
X655242Y-324537D01*
X655254Y-324541D01*
X655268Y-324545D01*
X655287Y-324548D01*
X655313Y-324556D01*
X655339Y-324563D01*
X655368Y-324570D01*
X655442Y-324582D01*
X655527Y-324593D01*
X655623Y-324600D01*
X655727Y-324604D01*
X655731D01*
X655746D01*
X655764D01*
X655794Y-324600D01*
X655827D01*
X655864Y-324596D01*
X655908Y-324593D01*
X655953Y-324589D01*
X656053Y-324570D01*
X656156Y-324548D01*
X656252Y-324515D01*
X656301Y-324493D01*
X656341Y-324471D01*
X656345D01*
X656352Y-324463D01*
X656363Y-324456D01*
X656378Y-324448D01*
X656415Y-324419D01*
X656460Y-324382D01*
X656508Y-324334D01*
X656556Y-324278D01*
X656597Y-324215D01*
X656630Y-324149D01*
X656634Y-324141D01*
X656637Y-324123D01*
X656648Y-324089D01*
X656660Y-324041D01*
X656667Y-323982D01*
X656678Y-323908D01*
X656682Y-323864D01*
Y-323816D01*
X656685Y-323767D01*
Y-323176D01*
D02*
G37*
G36*
X572887Y-116188D02*
X572080D01*
Y-117035D01*
X572842D01*
X572887Y-117032D01*
X572938Y-117028D01*
X572998Y-117024D01*
X573057Y-117017D01*
X573116Y-117006D01*
X573168Y-116991D01*
X573175Y-116987D01*
X573190Y-116980D01*
X573212Y-116969D01*
X573242Y-116954D01*
X573275Y-116932D01*
X573308Y-116906D01*
X573342Y-116873D01*
X573368Y-116835D01*
X573371Y-116832D01*
X573379Y-116817D01*
X573390Y-116795D01*
X573405Y-116765D01*
X573416Y-116732D01*
X573427Y-116695D01*
X573434Y-116650D01*
X573438Y-116606D01*
Y-116602D01*
Y-116599D01*
X573434Y-116577D01*
X573430Y-116543D01*
X573423Y-116499D01*
X573405Y-116454D01*
X573382Y-116403D01*
X573349Y-116355D01*
X573305Y-116306D01*
X573297Y-116303D01*
X573279Y-116288D01*
X573249Y-116269D01*
X573201Y-116247D01*
X573145Y-116225D01*
X573071Y-116207D01*
X572986Y-116192D01*
X572887Y-116188D01*
D02*
G37*
G36*
X277196Y-365355D02*
X276349D01*
Y-366117D01*
X276353Y-366161D01*
X276356Y-366213D01*
X276360Y-366272D01*
X276367Y-366332D01*
X276378Y-366391D01*
X276393Y-366443D01*
X276397Y-366450D01*
X276404Y-366465D01*
X276415Y-366487D01*
X276430Y-366517D01*
X276452Y-366550D01*
X276478Y-366583D01*
X276512Y-366617D01*
X276549Y-366642D01*
X276552Y-366646D01*
X276567Y-366654D01*
X276589Y-366665D01*
X276619Y-366680D01*
X276652Y-366691D01*
X276689Y-366702D01*
X276734Y-366709D01*
X276778Y-366713D01*
X276782D01*
X276785D01*
X276808Y-366709D01*
X276841Y-366705D01*
X276885Y-366698D01*
X276930Y-366680D01*
X276981Y-366657D01*
X277030Y-366624D01*
X277078Y-366580D01*
X277081Y-366572D01*
X277096Y-366554D01*
X277115Y-366524D01*
X277137Y-366476D01*
X277159Y-366421D01*
X277178Y-366347D01*
X277192Y-366261D01*
X277196Y-366161D01*
Y-365355D01*
D02*
G37*
G36*
X275823Y-369654D02*
Y-370461D01*
X276970D01*
X275823Y-369654D01*
D02*
G37*
G36*
X624257Y-140109D02*
X624228D01*
X624194Y-140117D01*
X624150Y-140124D01*
X624102Y-140139D01*
X624050Y-140157D01*
X624002Y-140187D01*
X623954Y-140228D01*
X623950Y-140232D01*
X623935Y-140246D01*
X623917Y-140272D01*
X623898Y-140305D01*
X623876Y-140346D01*
X623858Y-140394D01*
X623843Y-140446D01*
X623839Y-140505D01*
Y-140509D01*
Y-140513D01*
X623843Y-140535D01*
X623847Y-140568D01*
X623854Y-140609D01*
X623869Y-140657D01*
X623887Y-140705D01*
X623917Y-140757D01*
X623954Y-140801D01*
X623958Y-140805D01*
X623976Y-140820D01*
X624002Y-140838D01*
X624035Y-140857D01*
X624080Y-140879D01*
X624131Y-140898D01*
X624191Y-140912D01*
X624257Y-140916D01*
X624265D01*
X624287Y-140912D01*
X624320Y-140909D01*
X624365Y-140901D01*
X624413Y-140886D01*
X624461Y-140868D01*
X624513Y-140838D01*
X624557Y-140801D01*
X624561Y-140798D01*
X624576Y-140779D01*
X624594Y-140757D01*
X624616Y-140724D01*
X624638Y-140683D01*
X624657Y-140635D01*
X624672Y-140579D01*
X624675Y-140520D01*
Y-140516D01*
Y-140513D01*
Y-140490D01*
X624668Y-140457D01*
X624661Y-140417D01*
X624646Y-140372D01*
X624624Y-140324D01*
X624594Y-140276D01*
X624553Y-140228D01*
X624550Y-140224D01*
X624531Y-140209D01*
X624505Y-140191D01*
X624472Y-140169D01*
X624428Y-140146D01*
X624379Y-140128D01*
X624320Y-140113D01*
X624257Y-140109D01*
D02*
G37*
G36*
X624246Y-141171D02*
X624224D01*
X624209Y-141175D01*
X624168Y-141179D01*
X624117Y-141190D01*
X624057Y-141208D01*
X623998Y-141234D01*
X623935Y-141271D01*
X623880Y-141319D01*
X623873Y-141327D01*
X623858Y-141345D01*
X623836Y-141378D01*
X623810Y-141419D01*
X623780Y-141475D01*
X623758Y-141538D01*
X623743Y-141608D01*
X623736Y-141686D01*
Y-141693D01*
Y-141708D01*
X623739Y-141734D01*
X623743Y-141767D01*
X623750Y-141808D01*
X623762Y-141852D01*
X623776Y-141896D01*
X623795Y-141945D01*
X623799Y-141948D01*
X623806Y-141967D01*
X623821Y-141989D01*
X623843Y-142015D01*
X623869Y-142048D01*
X623902Y-142081D01*
X623939Y-142111D01*
X623983Y-142141D01*
X623991Y-142144D01*
X624006Y-142152D01*
X624032Y-142163D01*
X624065Y-142174D01*
X624106Y-142185D01*
X624154Y-142196D01*
X624205Y-142204D01*
X624257Y-142207D01*
X624279D01*
X624294Y-142204D01*
X624339Y-142200D01*
X624391Y-142189D01*
X624450Y-142170D01*
X624513Y-142148D01*
X624572Y-142111D01*
X624631Y-142063D01*
X624638Y-142056D01*
X624653Y-142037D01*
X624679Y-142004D01*
X624705Y-141963D01*
X624731Y-141911D01*
X624757Y-141848D01*
X624772Y-141774D01*
X624779Y-141697D01*
Y-141693D01*
Y-141686D01*
Y-141674D01*
X624775Y-141660D01*
X624772Y-141619D01*
X624760Y-141563D01*
X624742Y-141508D01*
X624716Y-141445D01*
X624679Y-141382D01*
X624627Y-141323D01*
X624620Y-141316D01*
X624601Y-141301D01*
X624568Y-141275D01*
X624524Y-141245D01*
X624468Y-141219D01*
X624402Y-141193D01*
X624328Y-141179D01*
X624246Y-141171D01*
D02*
G37*
G36*
X207210Y-378156D02*
X206064D01*
Y-378963D01*
X207210Y-378156D01*
D02*
G37*
G36*
Y-380147D02*
X206064D01*
Y-380953D01*
X207210Y-380147D01*
D02*
G37*
G36*
X210459Y-368377D02*
X209312D01*
Y-369184D01*
X210459Y-368377D01*
D02*
G37*
G36*
X217897Y-377810D02*
X217882D01*
X217875D01*
X217871D01*
X217771Y-377818D01*
X217686Y-377832D01*
X217612Y-377855D01*
X217549Y-377881D01*
X217501Y-377910D01*
X217464Y-377932D01*
X217442Y-377947D01*
X217438Y-377955D01*
X217435D01*
X217405Y-377980D01*
X217383Y-378010D01*
X217342Y-378069D01*
X217316Y-378128D01*
X217294Y-378180D01*
X217283Y-378228D01*
X217279Y-378265D01*
X217275Y-378280D01*
Y-378299D01*
X217279Y-378350D01*
X217286Y-378398D01*
X217301Y-378443D01*
X217316Y-378480D01*
X217327Y-378513D01*
X217342Y-378539D01*
X217349Y-378554D01*
X217353Y-378561D01*
X217386Y-378606D01*
X217420Y-378643D01*
X217460Y-378676D01*
X217494Y-378702D01*
X217527Y-378724D01*
X217553Y-378739D01*
X217571Y-378750D01*
X217579Y-378754D01*
X217634Y-378776D01*
X217690Y-378791D01*
X217742Y-378805D01*
X217790Y-378813D01*
X217830Y-378817D01*
X217864Y-378820D01*
X217882D01*
X217890D01*
X217978Y-378813D01*
X218056Y-378798D01*
X218126Y-378772D01*
X218182Y-378746D01*
X218230Y-378720D01*
X218263Y-378695D01*
X218282Y-378680D01*
X218289Y-378672D01*
X218341Y-378613D01*
X218378Y-378554D01*
X218408Y-378491D01*
X218426Y-378435D01*
X218437Y-378384D01*
X218441Y-378347D01*
X218444Y-378332D01*
Y-378310D01*
X218437Y-378232D01*
X218419Y-378162D01*
X218396Y-378102D01*
X218367Y-378051D01*
X218337Y-378010D01*
X218315Y-377980D01*
X218297Y-377962D01*
X218289Y-377955D01*
X218226Y-377906D01*
X218160Y-377869D01*
X218089Y-377843D01*
X218023Y-377829D01*
X217964Y-377818D01*
X217938Y-377814D01*
X217916D01*
X217897Y-377810D01*
D02*
G37*
G36*
X219111Y-380152D02*
X217964D01*
Y-380959D01*
X219111Y-380152D01*
D02*
G37*
G36*
X222145Y-365338D02*
X221297D01*
Y-366101D01*
X221301Y-366145D01*
X221305Y-366197D01*
X221308Y-366256D01*
X221316Y-366315D01*
X221327Y-366374D01*
X221342Y-366426D01*
X221345Y-366434D01*
X221353Y-366448D01*
X221364Y-366471D01*
X221379Y-366500D01*
X221391Y-366518D01*
X221483Y-366488D01*
X221642Y-366429D01*
X221720Y-366399D01*
X221794Y-366370D01*
X221860Y-366336D01*
X221927Y-366307D01*
X221986Y-366281D01*
X222038Y-366255D01*
X222082Y-366233D01*
X222123Y-366214D01*
X222142Y-366204D01*
X222145Y-366145D01*
Y-365338D01*
D02*
G37*
G36*
X221035Y-366322D02*
X221031Y-366330D01*
X221024Y-366345D01*
X221009Y-366367D01*
X220994Y-366396D01*
X220953Y-366463D01*
X220927Y-366496D01*
X220905Y-366526D01*
X220898Y-366533D01*
X220879Y-366552D01*
X220849Y-366582D01*
X220813Y-366618D01*
X220776Y-366647D01*
X220880Y-366633D01*
X220998Y-366614D01*
X221054Y-366603D01*
X221101Y-366593D01*
X221090Y-366563D01*
X221075Y-366508D01*
X221057Y-366452D01*
X221046Y-366389D01*
X221035Y-366322D01*
D02*
G37*
G36*
X221224Y-368349D02*
X221068D01*
X221097Y-368380D01*
X221186Y-368472D01*
X221224Y-368510D01*
Y-368349D01*
D02*
G37*
G36*
X222659D02*
X222438D01*
X222437Y-368357D01*
X222433Y-368387D01*
X222429Y-368424D01*
X222422Y-368465D01*
X222415Y-368506D01*
X222409Y-368525D01*
X222659Y-368349D01*
D02*
G37*
G36*
X222179D02*
X221512D01*
Y-368716D01*
X221538Y-368727D01*
X221601Y-368753D01*
X221671Y-368768D01*
X221738Y-368776D01*
X221741D01*
X221745D01*
X221767Y-368772D01*
X221804Y-368768D01*
X221845Y-368757D01*
X221897Y-368742D01*
X221949Y-368716D01*
X222000Y-368683D01*
X222052Y-368639D01*
X222059Y-368631D01*
X222074Y-368613D01*
X222093Y-368587D01*
X222119Y-368546D01*
X222141Y-368494D01*
X222163Y-368435D01*
X222178Y-368365D01*
X222179Y-368349D01*
D02*
G37*
G36*
X221512Y-369061D02*
Y-369156D01*
X221611Y-369086D01*
X221590Y-369083D01*
X221538Y-369068D01*
X221512Y-369061D01*
D02*
G37*
G36*
X221105Y-370170D02*
X221087Y-370188D01*
X221065Y-370207D01*
X221046Y-370221D01*
X221035Y-370236D01*
X221024Y-370247D01*
X221020Y-370251D01*
X221017Y-370255D01*
X220987Y-370292D01*
X220965Y-370333D01*
X220924Y-370414D01*
X220895Y-370492D01*
X220876Y-370569D01*
X220861Y-370636D01*
X220858Y-370662D01*
Y-370688D01*
X220854Y-370710D01*
Y-370728D01*
X220861Y-370725D01*
X220920Y-370689D01*
X220975Y-370640D01*
X220983Y-370633D01*
X220998Y-370615D01*
X221020Y-370585D01*
X221046Y-370544D01*
X221072Y-370492D01*
X221094Y-370429D01*
X221109Y-370359D01*
X221116Y-370282D01*
Y-370248D01*
X221112Y-370222D01*
X221109Y-370189D01*
X221105Y-370170D01*
D02*
G37*
G36*
X222414Y-370032D02*
X222415Y-370034D01*
X222433Y-370133D01*
X222441Y-370185D01*
Y-370278D01*
X222437Y-370319D01*
X222429Y-370367D01*
X222418Y-370426D01*
X222400Y-370492D01*
X222378Y-370559D01*
X222348Y-370626D01*
Y-370629D01*
X222344Y-370633D01*
X222333Y-370655D01*
X222311Y-370689D01*
X222285Y-370725D01*
X222248Y-370770D01*
X222207Y-370814D01*
X222159Y-370859D01*
X222104Y-370896D01*
X222096Y-370899D01*
X222078Y-370911D01*
X222045Y-370925D01*
X222004Y-370944D01*
X221956Y-370962D01*
X221900Y-370977D01*
X221837Y-370988D01*
X221775Y-370992D01*
X221767D01*
X221745D01*
X221715Y-370988D01*
X221675Y-370981D01*
X221626Y-370970D01*
X221575Y-370951D01*
X221523Y-370929D01*
X221471Y-370899D01*
X221464Y-370896D01*
X221449Y-370885D01*
X221423Y-370862D01*
X221393Y-370833D01*
X221360Y-370796D01*
X221323Y-370751D01*
X221290Y-370700D01*
X221257Y-370637D01*
Y-370640D01*
X221253Y-370648D01*
X221249Y-370659D01*
X221245Y-370674D01*
X221231Y-370714D01*
X221208Y-370766D01*
X221179Y-370825D01*
X221142Y-370885D01*
X221094Y-370940D01*
X221038Y-370992D01*
X221031Y-370996D01*
X221009Y-371010D01*
X220972Y-371033D01*
X220923Y-371055D01*
X220919Y-371057D01*
X220935Y-371095D01*
X220946Y-371117D01*
X220954Y-371135D01*
X220961Y-371150D01*
X220969Y-371161D01*
X220972Y-371169D01*
Y-371172D01*
X221024Y-371243D01*
X221080Y-371302D01*
X221143Y-371354D01*
X221202Y-371394D01*
X221253Y-371428D01*
X221298Y-371450D01*
X221316Y-371457D01*
X221327Y-371465D01*
X221335Y-371468D01*
X221339D01*
X221435Y-371498D01*
X221531Y-371520D01*
X221627Y-371539D01*
X221716Y-371550D01*
X221757Y-371553D01*
X221794Y-371557D01*
X221827D01*
X221853Y-371561D01*
X221875D01*
X221894D01*
X221905D01*
X221908D01*
X222005Y-371557D01*
X222093Y-371550D01*
X222175Y-371535D01*
X222249Y-371520D01*
X222312Y-371509D01*
X222338Y-371502D01*
X222360Y-371494D01*
X222378Y-371491D01*
X222389Y-371487D01*
X222397Y-371483D01*
X222400D01*
X222486Y-371446D01*
X222563Y-371406D01*
X222626Y-371361D01*
X222682Y-371313D01*
X222726Y-371272D01*
X222756Y-371239D01*
X222774Y-371213D01*
X222782Y-371209D01*
Y-371206D01*
X222830Y-371128D01*
X222867Y-371043D01*
X222892Y-370961D01*
X222907Y-370884D01*
X222918Y-370813D01*
X222922Y-370784D01*
Y-370758D01*
X222926Y-370740D01*
Y-370710D01*
X222922Y-370617D01*
X222907Y-370532D01*
X222885Y-370462D01*
X222863Y-370399D01*
X222837Y-370351D01*
X222819Y-370314D01*
X222804Y-370292D01*
X222796Y-370284D01*
X222741Y-370225D01*
X222678Y-370170D01*
X222611Y-370125D01*
X222545Y-370088D01*
X222486Y-370059D01*
X222456Y-370048D01*
X222434Y-370040D01*
X222415Y-370033D01*
X222414Y-370032D01*
D02*
G37*
G36*
X237841Y-366113D02*
X237819D01*
X237815D01*
X237811D01*
X237752Y-366116D01*
X237697Y-366131D01*
X237649Y-366150D01*
X237608Y-366172D01*
X237575Y-366194D01*
X237552Y-366213D01*
X237534Y-366227D01*
X237530Y-366231D01*
X237493Y-366276D01*
X237464Y-366327D01*
X237445Y-366375D01*
X237430Y-366424D01*
X237423Y-366468D01*
X237419Y-366501D01*
X237416Y-366523D01*
Y-366531D01*
X237419Y-366597D01*
X237434Y-366657D01*
X237453Y-366708D01*
X237475Y-366753D01*
X237493Y-366786D01*
X237512Y-366812D01*
X237526Y-366830D01*
X237530Y-366834D01*
X237575Y-366871D01*
X237626Y-366901D01*
X237674Y-366919D01*
X237723Y-366934D01*
X237763Y-366941D01*
X237797Y-366945D01*
X237819Y-366949D01*
X237823D01*
X237826D01*
X237885Y-366945D01*
X237937Y-366930D01*
X237985Y-366912D01*
X238026Y-366890D01*
X238059Y-366871D01*
X238085Y-366853D01*
X238100Y-366838D01*
X238104Y-366834D01*
X238144Y-366786D01*
X238174Y-366738D01*
X238193Y-366686D01*
X238207Y-366638D01*
X238215Y-366594D01*
X238222Y-366560D01*
Y-366531D01*
X238218Y-366468D01*
X238204Y-366409D01*
X238185Y-366361D01*
X238163Y-366316D01*
X238141Y-366283D01*
X238122Y-366257D01*
X238107Y-366238D01*
X238104Y-366235D01*
X238056Y-366194D01*
X238007Y-366164D01*
X237959Y-366142D01*
X237915Y-366127D01*
X237874Y-366120D01*
X237841Y-366113D01*
D02*
G37*
G36*
X236657Y-366009D02*
X236646D01*
X236638D01*
X236635D01*
X236557Y-366017D01*
X236483Y-366031D01*
X236420Y-366057D01*
X236368Y-366083D01*
X236328Y-366109D01*
X236294Y-366135D01*
X236276Y-366150D01*
X236268Y-366157D01*
X236220Y-366216D01*
X236183Y-366276D01*
X236161Y-366338D01*
X236143Y-366398D01*
X236132Y-366449D01*
X236128Y-366494D01*
X236124Y-366509D01*
Y-366531D01*
X236128Y-366583D01*
X236135Y-366634D01*
X236146Y-366683D01*
X236157Y-366723D01*
X236169Y-366757D01*
X236180Y-366782D01*
X236187Y-366797D01*
X236191Y-366805D01*
X236220Y-366849D01*
X236250Y-366886D01*
X236283Y-366919D01*
X236317Y-366945D01*
X236343Y-366967D01*
X236365Y-366982D01*
X236383Y-366990D01*
X236387Y-366993D01*
X236435Y-367012D01*
X236479Y-367027D01*
X236524Y-367038D01*
X236564Y-367045D01*
X236598Y-367049D01*
X236624Y-367053D01*
X236638D01*
X236646D01*
X236724Y-367045D01*
X236794Y-367030D01*
X236857Y-367008D01*
X236912Y-366979D01*
X236953Y-366953D01*
X236986Y-366930D01*
X237005Y-366916D01*
X237012Y-366908D01*
X237060Y-366853D01*
X237097Y-366790D01*
X237123Y-366731D01*
X237142Y-366671D01*
X237153Y-366620D01*
X237157Y-366579D01*
X237160Y-366564D01*
Y-366542D01*
X237153Y-366460D01*
X237138Y-366387D01*
X237112Y-366320D01*
X237086Y-366264D01*
X237057Y-366220D01*
X237031Y-366187D01*
X237016Y-366168D01*
X237009Y-366161D01*
X236949Y-366109D01*
X236886Y-366072D01*
X236824Y-366046D01*
X236768Y-366028D01*
X236713Y-366017D01*
X236672Y-366013D01*
X236657Y-366009D01*
D02*
G37*
G36*
X237959Y-368355D02*
X236812D01*
Y-369162D01*
X237959Y-368355D01*
D02*
G37*
G36*
X241656Y-366035D02*
X241641D01*
X241634D01*
X241630D01*
X241534Y-366042D01*
X241449Y-366057D01*
X241378Y-366079D01*
X241319Y-366105D01*
X241271Y-366135D01*
X241238Y-366157D01*
X241216Y-366172D01*
X241208Y-366179D01*
X241157Y-366235D01*
X241120Y-366294D01*
X241094Y-366353D01*
X241075Y-366412D01*
X241064Y-366460D01*
X241060Y-366501D01*
X241057Y-366516D01*
Y-366538D01*
X241064Y-366616D01*
X241079Y-366686D01*
X241105Y-366749D01*
X241134Y-366805D01*
X241160Y-366845D01*
X241186Y-366879D01*
X241201Y-366897D01*
X241208Y-366904D01*
X241267Y-366953D01*
X241334Y-366990D01*
X241401Y-367012D01*
X241464Y-367030D01*
X241519Y-367041D01*
X241541Y-367045D01*
X241564D01*
X241582Y-367049D01*
X241593D01*
X241600D01*
X241604D01*
X241700Y-367041D01*
X241789Y-367027D01*
X241867Y-367001D01*
X241930Y-366971D01*
X241982Y-366945D01*
X242019Y-366919D01*
X242030Y-366912D01*
X242041Y-366904D01*
X242044Y-366897D01*
X242048D01*
X242078Y-366867D01*
X242107Y-366838D01*
X242148Y-366775D01*
X242181Y-366712D01*
X242200Y-366653D01*
X242215Y-366605D01*
X242218Y-366564D01*
X242222Y-366549D01*
Y-366490D01*
X242215Y-366453D01*
X242196Y-366387D01*
X242170Y-366327D01*
X242144Y-366276D01*
X242115Y-366235D01*
X242089Y-366205D01*
X242070Y-366187D01*
X242067Y-366179D01*
X242063D01*
X242000Y-366131D01*
X241930Y-366094D01*
X241856Y-366068D01*
X241786Y-366054D01*
X241726Y-366042D01*
X241700Y-366039D01*
X241674D01*
X241656Y-366035D01*
D02*
G37*
G36*
X241959Y-368355D02*
X240812D01*
Y-369162D01*
X241959Y-368355D01*
D02*
G37*
G36*
X252730Y-366003D02*
X252697D01*
X252679D01*
X252675D01*
X252671D01*
X252557D01*
X252453Y-366011D01*
X252361Y-366018D01*
X252272Y-366026D01*
X252198Y-366037D01*
X252127Y-366052D01*
X252068Y-366066D01*
X252013Y-366077D01*
X251968Y-366092D01*
X251931Y-366107D01*
X251898Y-366118D01*
X251872Y-366133D01*
X251854Y-366140D01*
X251842Y-366148D01*
X251835Y-366155D01*
X251831D01*
X251795Y-366185D01*
X251765Y-366214D01*
X251735Y-366244D01*
X251713Y-366274D01*
X251676Y-366336D01*
X251650Y-366392D01*
X251635Y-366444D01*
X251628Y-366481D01*
X251624Y-366496D01*
Y-366518D01*
X251628Y-366559D01*
X251632Y-366596D01*
X251658Y-366666D01*
X251691Y-366729D01*
X251728Y-366784D01*
X251765Y-366825D01*
X251798Y-366858D01*
X251824Y-366877D01*
X251828Y-366884D01*
X251831D01*
X251876Y-366910D01*
X251928Y-366932D01*
X251987Y-366954D01*
X252050Y-366969D01*
X252116Y-366984D01*
X252187Y-366995D01*
X252331Y-367014D01*
X252398Y-367021D01*
X252460Y-367025D01*
X252520Y-367028D01*
X252568D01*
X252612Y-367032D01*
X252645D01*
X252664D01*
X252671D01*
X252786Y-367028D01*
X252890Y-367025D01*
X252986Y-367017D01*
X253075Y-367006D01*
X253152Y-366995D01*
X253223Y-366980D01*
X253286Y-366966D01*
X253341Y-366951D01*
X253389Y-366936D01*
X253430Y-366925D01*
X253463Y-366910D01*
X253493Y-366899D01*
X253511Y-366888D01*
X253526Y-366880D01*
X253533Y-366873D01*
X253537D01*
X253570Y-366847D01*
X253600Y-366821D01*
X253622Y-366792D01*
X253644Y-366762D01*
X253678Y-366703D01*
X253700Y-366647D01*
X253711Y-366599D01*
X253718Y-366559D01*
X253722Y-366544D01*
Y-366522D01*
X253718Y-366481D01*
X253715Y-366440D01*
X253704Y-366403D01*
X253689Y-366370D01*
X253656Y-366307D01*
X253619Y-366251D01*
X253578Y-366211D01*
X253544Y-366177D01*
X253530Y-366166D01*
X253519Y-366159D01*
X253515Y-366151D01*
X253511D01*
X253467Y-366126D01*
X253415Y-366103D01*
X253356Y-366081D01*
X253293Y-366066D01*
X253226Y-366052D01*
X253156Y-366040D01*
X253015Y-366022D01*
X252945Y-366015D01*
X252882Y-366011D01*
X252823Y-366007D01*
X252775D01*
X252730Y-366003D01*
D02*
G37*
G36*
X622587Y-123433D02*
X621980D01*
X621954Y-123436D01*
X621898Y-123440D01*
X621836Y-123444D01*
X621769Y-123451D01*
X621702Y-123462D01*
X621647Y-123477D01*
X621639Y-123481D01*
X621621Y-123484D01*
X621595Y-123496D01*
X621562Y-123510D01*
X621525Y-123532D01*
X621488Y-123555D01*
X621451Y-123581D01*
X621414Y-123610D01*
X621410Y-123618D01*
X621395Y-123632D01*
X621373Y-123658D01*
X621347Y-123695D01*
X621317Y-123743D01*
X621284Y-123799D01*
X621255Y-123862D01*
X621229Y-123932D01*
Y-123936D01*
X621225Y-123943D01*
X621221Y-123954D01*
X621218Y-123969D01*
X621214Y-123988D01*
X621207Y-124014D01*
X621199Y-124039D01*
X621192Y-124069D01*
X621181Y-124143D01*
X621170Y-124228D01*
X621162Y-124324D01*
X621158Y-124428D01*
Y-124432D01*
Y-124446D01*
Y-124465D01*
X621162Y-124495D01*
Y-124528D01*
X621166Y-124565D01*
X621170Y-124609D01*
X621173Y-124654D01*
X621192Y-124753D01*
X621214Y-124857D01*
X621247Y-124953D01*
X621269Y-125001D01*
X621292Y-125042D01*
Y-125046D01*
X621299Y-125053D01*
X621306Y-125064D01*
X621314Y-125079D01*
X621343Y-125116D01*
X621380Y-125161D01*
X621428Y-125209D01*
X621484Y-125257D01*
X621547Y-125297D01*
X621614Y-125331D01*
X621621Y-125334D01*
X621639Y-125338D01*
X621673Y-125349D01*
X621721Y-125360D01*
X621780Y-125368D01*
X621854Y-125379D01*
X621898Y-125382D01*
X621946D01*
X621995Y-125386D01*
X622587D01*
Y-123433D01*
D02*
G37*
G36*
X620274Y-124032D02*
X619467D01*
Y-125179D01*
X620274Y-124032D01*
D02*
G37*
G36*
X620344Y-117317D02*
X619538D01*
Y-118165D01*
X620300D01*
X620344Y-118161D01*
X620396Y-118157D01*
X620456Y-118154D01*
X620515Y-118146D01*
X620574Y-118135D01*
X620626Y-118120D01*
X620633Y-118117D01*
X620648Y-118109D01*
X620670Y-118098D01*
X620700Y-118083D01*
X620733Y-118061D01*
X620766Y-118035D01*
X620800Y-118002D01*
X620825Y-117965D01*
X620829Y-117961D01*
X620837Y-117946D01*
X620848Y-117924D01*
X620862Y-117895D01*
X620874Y-117861D01*
X620885Y-117824D01*
X620892Y-117780D01*
X620896Y-117735D01*
Y-117732D01*
Y-117728D01*
X620892Y-117706D01*
X620888Y-117673D01*
X620881Y-117628D01*
X620862Y-117584D01*
X620840Y-117532D01*
X620807Y-117484D01*
X620763Y-117436D01*
X620755Y-117432D01*
X620737Y-117417D01*
X620707Y-117399D01*
X620659Y-117376D01*
X620604Y-117354D01*
X620530Y-117336D01*
X620444Y-117321D01*
X620344Y-117317D01*
D02*
G37*
G36*
X545038Y-128570D02*
X544275D01*
X544231Y-128574D01*
X544179Y-128578D01*
X544120Y-128581D01*
X544061Y-128589D01*
X544002Y-128600D01*
X543950Y-128615D01*
X543942Y-128618D01*
X543928Y-128626D01*
X543905Y-128637D01*
X543876Y-128652D01*
X543843Y-128674D01*
X543809Y-128700D01*
X543776Y-128733D01*
X543750Y-128770D01*
X543746Y-128774D01*
X543739Y-128788D01*
X543728Y-128811D01*
X543713Y-128840D01*
X543702Y-128874D01*
X543691Y-128911D01*
X543683Y-128955D01*
X543680Y-128999D01*
Y-129003D01*
Y-129007D01*
X543683Y-129029D01*
X543687Y-129062D01*
X543694Y-129107D01*
X543713Y-129151D01*
X543735Y-129203D01*
X543769Y-129251D01*
X543813Y-129299D01*
X543820Y-129303D01*
X543839Y-129318D01*
X543868Y-129336D01*
X543917Y-129358D01*
X543972Y-129381D01*
X544046Y-129399D01*
X544131Y-129414D01*
X544231Y-129418D01*
X545038D01*
Y-128570D01*
D02*
G37*
G36*
X573193Y-139146D02*
X573189D01*
X573185D01*
X573163Y-139149D01*
X573130Y-139153D01*
X573086Y-139161D01*
X573041Y-139179D01*
X572989Y-139201D01*
X572941Y-139235D01*
X572893Y-139279D01*
X572890Y-139286D01*
X572875Y-139305D01*
X572856Y-139334D01*
X572834Y-139383D01*
X572812Y-139438D01*
X572793Y-139512D01*
X572779Y-139597D01*
X572775Y-139697D01*
Y-140504D01*
X573622D01*
Y-139742D01*
X573618Y-139697D01*
X573615Y-139645D01*
X573611Y-139586D01*
X573604Y-139527D01*
X573593Y-139468D01*
X573578Y-139416D01*
X573574Y-139409D01*
X573567Y-139394D01*
X573556Y-139372D01*
X573541Y-139342D01*
X573519Y-139309D01*
X573493Y-139275D01*
X573459Y-139242D01*
X573422Y-139216D01*
X573419Y-139212D01*
X573404Y-139205D01*
X573382Y-139194D01*
X573352Y-139179D01*
X573319Y-139168D01*
X573282Y-139157D01*
X573237Y-139149D01*
X573193Y-139146D01*
D02*
G37*
G36*
X562712Y-105198D02*
X562690D01*
X562675Y-105202D01*
X562634Y-105206D01*
X562586Y-105217D01*
X562527Y-105235D01*
X562468Y-105261D01*
X562409Y-105298D01*
X562353Y-105350D01*
X562346Y-105358D01*
X562331Y-105380D01*
X562309Y-105413D01*
X562279Y-105461D01*
X562253Y-105520D01*
X562231Y-105591D01*
X562216Y-105676D01*
X562209Y-105772D01*
Y-105776D01*
Y-105783D01*
Y-105798D01*
X562213Y-105816D01*
Y-105842D01*
X562216Y-105868D01*
X562227Y-105927D01*
X562242Y-105998D01*
X562268Y-106072D01*
X562305Y-106142D01*
X562353Y-106205D01*
Y-106209D01*
X562361Y-106212D01*
X562379Y-106231D01*
X562409Y-106257D01*
X562449Y-106286D01*
X562501Y-106312D01*
X562560Y-106338D01*
X562627Y-106357D01*
X562664Y-106364D01*
X562723D01*
X562738Y-106360D01*
X562779Y-106357D01*
X562827Y-106342D01*
X562886Y-106323D01*
X562949Y-106290D01*
X563012Y-106249D01*
X563041Y-106220D01*
X563071Y-106190D01*
Y-106186D01*
X563078Y-106183D01*
X563086Y-106172D01*
X563093Y-106160D01*
X563119Y-106123D01*
X563145Y-106072D01*
X563175Y-106009D01*
X563201Y-105931D01*
X563215Y-105842D01*
X563223Y-105746D01*
Y-105742D01*
Y-105735D01*
Y-105724D01*
X563219Y-105705D01*
Y-105683D01*
X563215Y-105661D01*
X563204Y-105605D01*
X563186Y-105543D01*
X563164Y-105476D01*
X563127Y-105409D01*
X563078Y-105350D01*
X563071Y-105343D01*
X563053Y-105328D01*
X563019Y-105302D01*
X562979Y-105276D01*
X562923Y-105246D01*
X562860Y-105221D01*
X562790Y-105206D01*
X562712Y-105198D01*
D02*
G37*
G36*
X565654Y-105480D02*
X564891D01*
X564847Y-105483D01*
X564795Y-105487D01*
X564736Y-105491D01*
X564677Y-105498D01*
X564618Y-105509D01*
X564566Y-105524D01*
X564558Y-105528D01*
X564544Y-105535D01*
X564521Y-105546D01*
X564492Y-105561D01*
X564459Y-105583D01*
X564425Y-105609D01*
X564392Y-105642D01*
X564366Y-105679D01*
X564362Y-105683D01*
X564355Y-105698D01*
X564344Y-105720D01*
X564329Y-105750D01*
X564318Y-105783D01*
X564307Y-105820D01*
X564299Y-105864D01*
X564296Y-105909D01*
Y-105912D01*
Y-105916D01*
X564299Y-105938D01*
X564303Y-105972D01*
X564311Y-106016D01*
X564329Y-106061D01*
X564351Y-106112D01*
X564385Y-106160D01*
X564429Y-106209D01*
X564436Y-106212D01*
X564455Y-106227D01*
X564484Y-106246D01*
X564533Y-106268D01*
X564588Y-106290D01*
X564662Y-106308D01*
X564747Y-106323D01*
X564847Y-106327D01*
X565654D01*
Y-105480D01*
D02*
G37*
G36*
X116132Y-263774D02*
X115370D01*
X115325Y-263778D01*
X115273Y-263781D01*
X115214Y-263785D01*
X115155Y-263792D01*
X115096Y-263804D01*
X115044Y-263818D01*
X115037Y-263822D01*
X115022Y-263829D01*
X114999Y-263841D01*
X114970Y-263855D01*
X114937Y-263878D01*
X114903Y-263903D01*
X114870Y-263937D01*
X114844Y-263974D01*
X114840Y-263978D01*
X114833Y-263992D01*
X114822Y-264015D01*
X114807Y-264044D01*
X114796Y-264077D01*
X114785Y-264114D01*
X114778Y-264159D01*
X114774Y-264203D01*
Y-264207D01*
Y-264211D01*
X114778Y-264233D01*
X114781Y-264266D01*
X114789Y-264311D01*
X114807Y-264355D01*
X114829Y-264407D01*
X114863Y-264455D01*
X114907Y-264503D01*
X114915Y-264507D01*
X114933Y-264521D01*
X114963Y-264540D01*
X115011Y-264562D01*
X115066Y-264584D01*
X115140Y-264603D01*
X115225Y-264618D01*
X115325Y-264621D01*
X116132D01*
Y-263774D01*
D02*
G37*
%LPD*%
D13*
X547126Y-343543D02*
G03*
X547126Y-343543I-394J0D01*
G01*
X-20374Y-188583D02*
Y-175984D01*
X-16437D01*
Y-188583D02*
Y-175984D01*
X-20374Y-188583D02*
X-16437D01*
X-20374Y-241339D02*
Y-228740D01*
X-16437D01*
Y-241339D02*
Y-228740D01*
X-20374Y-241339D02*
X-16437D01*
X-20374Y-294882D02*
Y-282283D01*
X-16437D01*
Y-294882D02*
Y-282283D01*
X-20374Y-294882D02*
X-16437D01*
X-20374Y-347638D02*
Y-335039D01*
X-16437D01*
Y-347638D02*
Y-335039D01*
X-20374Y-347638D02*
X-16437D01*
X-20374Y-114764D02*
Y-102165D01*
X-16437D01*
Y-114764D02*
Y-102165D01*
X-20374Y-114764D02*
X-16437D01*
X-20374Y-71457D02*
Y-58858D01*
X-16437D01*
Y-71457D02*
Y-58858D01*
X-20374Y-71457D02*
X-16437D01*
D14*
X99016Y-119685D02*
G03*
X99016Y-119685I-1969J0D01*
G01*
X286614Y-115147D02*
G03*
X286614Y-115147I-1969J0D01*
G01*
X216142Y-115600D02*
G03*
X216142Y-115600I-1969J0D01*
G01*
X335236Y-121260D02*
X348228D01*
X335236Y-128347D02*
X348228D01*
X335236D02*
Y-121260D01*
X348228Y-128347D02*
Y-121260D01*
X359252Y-139764D02*
Y-132677D01*
X372244Y-139764D02*
Y-132677D01*
X359252D02*
X372244D01*
X359252Y-139764D02*
X372244D01*
X637795Y-235433D02*
X641732D01*
X637795Y-242520D02*
X641732D01*
Y-235433D01*
X637795Y-242520D02*
Y-235433D01*
X552450Y-215862D02*
X556387D01*
X552450Y-222949D02*
X556387D01*
Y-215862D01*
X552450Y-222949D02*
Y-215862D01*
X600950Y-244449D02*
X604887D01*
X600950Y-237362D02*
X604887D01*
X600950Y-244449D02*
Y-237362D01*
X604887Y-244449D02*
Y-237362D01*
X584450Y-244449D02*
X588387D01*
X584450Y-237362D02*
X588387D01*
X584450Y-244449D02*
Y-237362D01*
X588387Y-244449D02*
Y-237362D01*
X594950Y-244449D02*
X598887D01*
X594950Y-237362D02*
X598887D01*
X594950Y-244449D02*
Y-237362D01*
X598887Y-244449D02*
Y-237362D01*
X589950Y-244449D02*
X593887D01*
X589950Y-237362D02*
X593887D01*
X589950Y-244449D02*
Y-237362D01*
X593887Y-244449D02*
Y-237362D01*
X570072Y-214677D02*
Y-211134D01*
X576765Y-214677D02*
Y-211134D01*
X570072D02*
X576765D01*
X570072Y-214677D02*
X576765D01*
X654528Y-263779D02*
Y-256693D01*
X641535Y-263779D02*
Y-256693D01*
Y-263779D02*
X654528D01*
X641535Y-256693D02*
X654528D01*
X358465Y-128347D02*
Y-121260D01*
X371457Y-128347D02*
Y-121260D01*
X358465D02*
X371457D01*
X358465Y-128347D02*
X371457D01*
X647689Y-41840D02*
Y-9832D01*
X631941Y-41840D02*
Y-9832D01*
X647689D01*
X631941Y-41840D02*
X647689D01*
X549291Y-348287D02*
X629291D01*
Y-311791D01*
X549291D02*
X629291D01*
X549291Y-348287D02*
Y-311791D01*
X75736Y-45856D02*
X91484D01*
X75736Y-77864D02*
X91484D01*
Y-45856D01*
X75736Y-77864D02*
Y-45856D01*
X263397Y-134049D02*
Y-130506D01*
X256704Y-134049D02*
Y-130506D01*
Y-134049D02*
X263397D01*
X256704Y-130506D02*
X263397D01*
X248622Y-128937D02*
Y-125394D01*
X241929Y-128937D02*
Y-125394D01*
Y-128937D02*
X248622D01*
X241929Y-125394D02*
X248622D01*
X5315Y-330561D02*
Y-303002D01*
X-22244D02*
X5315D01*
X-22244Y-330561D02*
X5315D01*
X-22244D02*
Y-303002D01*
X5315Y-277410D02*
Y-249850D01*
X-22244D02*
X5315D01*
X-22244Y-277410D02*
X5315D01*
X-22244D02*
Y-249850D01*
X5315Y-224260D02*
Y-196701D01*
X-22244D02*
X5315D01*
X-22244Y-224260D02*
X5315D01*
X-22244D02*
Y-196701D01*
X5315Y-171112D02*
Y-143553D01*
X-22244D02*
X5315D01*
X-22244Y-171112D02*
X5315D01*
X-22244D02*
Y-143553D01*
X71260Y-216535D02*
X80315D01*
X71260D02*
Y-208661D01*
X80315D01*
Y-216535D02*
Y-208661D01*
X78347Y-216535D02*
X80315Y-214567D01*
X70276Y-163386D02*
X79331D01*
X70276D02*
Y-155512D01*
X79331D01*
Y-163386D02*
Y-155512D01*
X77362Y-163386D02*
X79331Y-161417D01*
X45374Y-5413D02*
X49114D01*
X45374Y1476D02*
X49114D01*
X45374Y-5413D02*
Y1476D01*
X49114Y-5413D02*
Y1476D01*
X38484Y-5413D02*
X42224D01*
X38484Y1476D02*
X42224D01*
X38484Y-5413D02*
Y1476D01*
X42224Y-5413D02*
Y1476D01*
X31594Y-5413D02*
X35335D01*
X31594Y1476D02*
X35335D01*
X31594Y-5413D02*
Y1476D01*
X35335Y-5413D02*
Y1476D01*
X24705Y-5413D02*
X28445D01*
X24705Y1476D02*
X28445D01*
X24705Y-5413D02*
Y1476D01*
X28445Y-5413D02*
Y1476D01*
X93504Y-135827D02*
Y-116142D01*
X113189Y-135827D02*
Y-116142D01*
X93504D02*
X113189D01*
X93504Y-135827D02*
X113189D01*
X76279Y-137697D02*
X83169D01*
X76279Y-133957D02*
X83169D01*
Y-137697D02*
Y-133957D01*
X76279Y-137697D02*
Y-133957D01*
X84646Y-129528D02*
Y-122441D01*
X80709Y-129528D02*
Y-122441D01*
X84646D01*
X80709Y-129528D02*
X84646D01*
X73876Y-117283D02*
Y-110197D01*
X77813Y-117283D02*
Y-110197D01*
X73876Y-117283D02*
X77813D01*
X73876Y-110197D02*
X77813D01*
X71260Y-268701D02*
X80315D01*
X71260D02*
Y-260827D01*
X80315D01*
Y-268701D02*
Y-260827D01*
X78347Y-268701D02*
X80315Y-266732D01*
X39173Y-267913D02*
X49409D01*
X39173D02*
Y-257677D01*
X49409D01*
Y-267913D02*
Y-257677D01*
X39173Y-162598D02*
X49409D01*
X39173D02*
Y-152362D01*
X49409D01*
Y-162598D02*
Y-152362D01*
X72933Y-336122D02*
Y-329232D01*
X76673Y-336122D02*
Y-329232D01*
X72933Y-336122D02*
X76673D01*
X72933Y-329232D02*
X76673D01*
X80807Y-336122D02*
Y-329232D01*
X84547Y-336122D02*
Y-329232D01*
X80807Y-336122D02*
X84547D01*
X80807Y-329232D02*
X84547D01*
X70276Y-322835D02*
X79331D01*
X70276D02*
Y-314961D01*
X79331D01*
Y-322835D02*
Y-314961D01*
X77362Y-322835D02*
X79331Y-320866D01*
X39173Y-322047D02*
X49409D01*
X39173D02*
Y-311811D01*
X49409D01*
Y-322047D02*
Y-311811D01*
X39173Y-215748D02*
X49409D01*
X39173D02*
Y-205512D01*
X49409D01*
Y-215748D02*
Y-205512D01*
X60236Y-318701D02*
Y-315158D01*
X53543Y-318701D02*
Y-315158D01*
Y-318701D02*
X60236D01*
X53543Y-315158D02*
X60236D01*
X61417Y-212402D02*
Y-208858D01*
X54724Y-212402D02*
Y-208858D01*
Y-212402D02*
X61417D01*
X54724Y-208858D02*
X61417D01*
Y-264567D02*
Y-261024D01*
X54724Y-264567D02*
Y-261024D01*
Y-264567D02*
X61417D01*
X54724Y-261024D02*
X61417D01*
X73917Y-227854D02*
Y-220965D01*
X77658Y-227854D02*
Y-220965D01*
X73917Y-227854D02*
X77658D01*
X73917Y-220965D02*
X77658D01*
X80807Y-227854D02*
Y-220965D01*
X84547Y-227854D02*
Y-220965D01*
X80807Y-227854D02*
X84547D01*
X80807Y-220965D02*
X84547D01*
X81791Y-281988D02*
Y-275098D01*
X85532Y-281988D02*
Y-275098D01*
X81791Y-281988D02*
X85532D01*
X81791Y-275098D02*
X85532D01*
X73917Y-281988D02*
Y-275098D01*
X77658Y-281988D02*
Y-275098D01*
X73917Y-281988D02*
X77658D01*
X73917Y-275098D02*
X77658D01*
X72933Y-175689D02*
Y-168799D01*
X76673Y-175689D02*
Y-168799D01*
X72933Y-175689D02*
X76673D01*
X72933Y-168799D02*
X76673D01*
X80807Y-175689D02*
Y-168799D01*
X84547Y-175689D02*
Y-168799D01*
X80807Y-175689D02*
X84547D01*
X80807Y-168799D02*
X84547D01*
X498032Y-138435D02*
X501968D01*
X498032Y-131348D02*
X501968D01*
X498032Y-138435D02*
Y-131348D01*
X501968Y-138435D02*
Y-131348D01*
X487992Y-139616D02*
Y-135679D01*
X480905Y-139616D02*
Y-135679D01*
Y-139616D02*
X487992D01*
X480905Y-135679D02*
X487992D01*
X462008Y-139517D02*
Y-135777D01*
X455315Y-139517D02*
Y-135777D01*
Y-139517D02*
X462008D01*
X455315Y-135777D02*
X462008D01*
X643898Y-52017D02*
X650984D01*
X643898Y-48080D02*
X650984D01*
Y-52017D02*
Y-48080D01*
X643898Y-52017D02*
Y-48080D01*
X609223Y-15985D02*
X616310D01*
X609223Y-12049D02*
X616310D01*
Y-15985D02*
Y-12049D01*
X609223Y-15985D02*
Y-12049D01*
X65945Y-336221D02*
Y-329134D01*
X69882Y-336221D02*
Y-329134D01*
X65945Y-336221D02*
X69882D01*
X65945Y-329134D02*
X69882D01*
X197933Y-120226D02*
Y-113730D01*
X201673Y-120226D02*
Y-113730D01*
X197933Y-120226D02*
X201673D01*
X197933Y-113730D02*
X201673D01*
X397736Y-135187D02*
X401476D01*
X397736Y-128297D02*
X401476D01*
X397736Y-135187D02*
Y-128297D01*
X401476Y-135187D02*
Y-128297D01*
X261417Y-128592D02*
X268110D01*
X261417Y-125049D02*
X268110D01*
Y-128592D02*
Y-125049D01*
X261417Y-128592D02*
Y-125049D01*
X281102Y-131289D02*
Y-111604D01*
X296850Y-131289D02*
Y-111604D01*
X281102D02*
X296850D01*
X281102Y-131289D02*
X296850D01*
X210630Y-131742D02*
Y-112057D01*
X226378Y-131742D02*
Y-112057D01*
X210630D02*
X226378D01*
X210630Y-131742D02*
X226378D01*
X560467Y-113177D02*
X567160D01*
X560467Y-109634D02*
X567160D01*
Y-113177D02*
Y-109634D01*
X560467Y-113177D02*
Y-109634D01*
X603691Y-142717D02*
Y-135630D01*
X599754Y-142717D02*
Y-135630D01*
X603691D01*
X599754Y-142717D02*
X603691D01*
X583219D02*
Y-135630D01*
X579282Y-142717D02*
Y-135630D01*
X583219D01*
X579282Y-142717D02*
X583219D01*
X590306D02*
Y-135630D01*
X586369Y-142717D02*
Y-135630D01*
X590306D01*
X586369Y-142717D02*
X590306D01*
X596998D02*
Y-135630D01*
X593061Y-142717D02*
Y-135630D01*
X596998D01*
X593061Y-142717D02*
X596998D01*
X542845Y-120949D02*
Y-113862D01*
X546782Y-120949D02*
Y-113862D01*
X542845Y-120949D02*
X546782D01*
X542845Y-113862D02*
X546782D01*
X116142Y-80167D02*
Y-73080D01*
X112205Y-80167D02*
Y-73080D01*
X116142D01*
X112205Y-80167D02*
X116142D01*
X100394Y-98868D02*
Y-91781D01*
X96457Y-98868D02*
Y-91781D01*
X100394D01*
X96457Y-98868D02*
X100394D01*
X346137Y-105025D02*
Y-97939D01*
X350075Y-105025D02*
Y-97939D01*
X346137Y-105025D02*
X350075D01*
X346137Y-97939D02*
X350075D01*
X445866Y-129379D02*
Y-122293D01*
X449803Y-129379D02*
Y-122293D01*
X445866Y-129379D02*
X449803D01*
X445866Y-122293D02*
X449803D01*
X263189Y-114025D02*
Y-110088D01*
X270276Y-114025D02*
Y-110088D01*
X263189D02*
X270276D01*
X263189Y-114025D02*
X270276D01*
X242126Y-114419D02*
X246063D01*
X242126Y-121505D02*
X246063D01*
Y-114419D01*
X242126Y-121505D02*
Y-114419D01*
X65945Y-168701D02*
X69882D01*
X65945Y-175787D02*
X69882D01*
Y-168701D01*
X65945Y-175787D02*
Y-168701D01*
X66929Y-275000D02*
X70866D01*
X66929Y-282087D02*
X70866D01*
Y-275000D01*
X66929Y-282087D02*
Y-275000D01*
X66929Y-220866D02*
X70866D01*
X66929Y-227953D02*
X70866D01*
Y-220866D01*
X66929Y-227953D02*
Y-220866D01*
X519488Y-114025D02*
Y-110088D01*
X512402Y-114025D02*
Y-110088D01*
Y-114025D02*
X519488D01*
X512402Y-110088D02*
X519488D01*
X526575Y-111269D02*
X530512D01*
X526575Y-118356D02*
X530512D01*
Y-111269D01*
X526575Y-118356D02*
Y-111269D01*
X261417Y-120718D02*
X268110D01*
X261417Y-117175D02*
X268110D01*
Y-120718D02*
Y-117175D01*
X261417Y-120718D02*
Y-117175D01*
X235433Y-126230D02*
Y-119537D01*
X238976Y-126230D02*
Y-119537D01*
X235433Y-126230D02*
X238976D01*
X235433Y-119537D02*
X238976D01*
X53740Y-155709D02*
X60433D01*
X53740Y-159252D02*
X60433D01*
X53740D02*
Y-155709D01*
X60433Y-159252D02*
Y-155709D01*
X403642Y-135187D02*
X407382D01*
X403642Y-128297D02*
X407382D01*
X403642Y-135187D02*
Y-128297D01*
X407382Y-135187D02*
Y-128297D01*
D178*
X556693Y-198819D02*
X607087D01*
X556693D02*
Y-148425D01*
X607087D01*
Y-198819D02*
Y-148425D01*
X581890Y-178622D02*
Y-168622D01*
X576890Y-173622D02*
X586890D01*
X549171Y-230035D02*
X555667D01*
X549171Y-233776D02*
X555667D01*
X549171D02*
Y-230035D01*
X555667Y-233776D02*
Y-230035D01*
X546588Y-238051D02*
X555250D01*
X546588Y-243760D02*
X555250D01*
X546588D02*
Y-238051D01*
X555250Y-243760D02*
Y-238051D01*
X608065Y-244736D02*
Y-236075D01*
X613773Y-244736D02*
Y-236075D01*
X608065Y-244736D02*
X613773D01*
X608065Y-236075D02*
X613773D01*
X619065Y-244736D02*
Y-236075D01*
X624773Y-244736D02*
Y-236075D01*
X619065Y-244736D02*
X624773D01*
X619065Y-236075D02*
X624773D01*
X584005Y-233760D02*
Y-227264D01*
X580265Y-233760D02*
Y-227264D01*
X584005D01*
X580265Y-233760D02*
X584005D01*
X584289Y-223153D02*
Y-216657D01*
X580549Y-223153D02*
Y-216657D01*
X584289D01*
X580549Y-223153D02*
X584289D01*
X570226Y-205020D02*
X576722D01*
X570226Y-208760D02*
X576722D01*
X570226D02*
Y-205020D01*
X576722Y-208760D02*
Y-205020D01*
X561974Y-256776D02*
X568864D01*
X561974Y-253035D02*
X568864D01*
Y-256776D02*
Y-253035D01*
X561974Y-256776D02*
Y-253035D01*
X593919Y-274905D02*
X603919D01*
X598919Y-279906D02*
Y-269905D01*
X624116Y-300102D02*
Y-249709D01*
X573722D02*
X624116D01*
X573722Y-300102D02*
Y-249709D01*
Y-300102D02*
X624116D01*
X621016Y-187988D02*
X675661D01*
Y-154760D01*
X621016D02*
X675661D01*
X621016Y-187988D02*
Y-154760D01*
X655925Y-181417D02*
Y-176417D01*
X653425Y-178917D02*
X658425D01*
X532225Y-334494D02*
X540887D01*
X532225Y-328982D02*
X540887D01*
Y-334494D02*
Y-328982D01*
X532225Y-334494D02*
Y-328982D01*
X531832Y-350636D02*
X540493D01*
X531832Y-345124D02*
X540493D01*
Y-350636D02*
Y-345124D01*
X531832Y-350636D02*
Y-345124D01*
X652362Y-346850D02*
Y-338189D01*
X657874Y-346850D02*
Y-338189D01*
X652362Y-346850D02*
X657874D01*
X652362Y-338189D02*
X657874D01*
X516969Y-336069D02*
Y-327407D01*
X522285Y-336069D02*
Y-327407D01*
X516969D02*
X522285D01*
X516969Y-336069D02*
X522285D01*
X516871Y-352210D02*
Y-343549D01*
X522186Y-352210D02*
Y-343549D01*
X516871D02*
X522186D01*
X516871Y-352210D02*
X522186D01*
X632677Y-322146D02*
X641339D01*
X632677Y-327461D02*
X641339D01*
Y-322146D01*
X632677Y-327461D02*
Y-322146D01*
X651378Y-322244D02*
X660039D01*
X651378Y-327559D02*
X660039D01*
Y-322244D01*
X651378Y-327559D02*
Y-322244D01*
X634252Y-347244D02*
Y-338583D01*
X639764Y-347244D02*
Y-338583D01*
X634252Y-347244D02*
X639764D01*
X634252Y-338583D02*
X639764D01*
X651279Y-242126D02*
Y-233465D01*
X645571Y-242126D02*
Y-233465D01*
X651279D01*
X645571Y-242126D02*
X651279D01*
X570565Y-119076D02*
Y-115335D01*
X577061Y-119076D02*
Y-115335D01*
X570565D02*
X577061D01*
X570565Y-119076D02*
X577061D01*
X275787Y-358316D02*
Y-353986D01*
X278150Y-358316D02*
Y-353986D01*
X275787Y-358316D02*
X278150D01*
X275787Y-353986D02*
X278150D01*
X654823Y-251476D02*
Y-247736D01*
X648327Y-251476D02*
Y-247736D01*
Y-251476D02*
X654823D01*
X648327Y-247736D02*
X654823D01*
X360335Y-104724D02*
Y-96063D01*
X354626Y-104724D02*
Y-96063D01*
X360335D01*
X354626Y-104724D02*
X360335D01*
X272260Y-382765D02*
X274622D01*
X272260Y-378435D02*
X274622D01*
Y-382765D02*
Y-378435D01*
X272260Y-382765D02*
Y-378435D01*
X546555Y-157382D02*
Y-150492D01*
X550295Y-157382D02*
Y-150492D01*
X546555Y-157382D02*
X550295D01*
X546555Y-150492D02*
X550295D01*
X546644Y-141260D02*
Y-135551D01*
X537983Y-141260D02*
Y-135551D01*
Y-141260D02*
X546644D01*
X537983Y-135551D02*
X546644D01*
X618652Y-135335D02*
Y-129626D01*
X627313Y-135335D02*
Y-129626D01*
X618652D02*
X627313D01*
X618652Y-135335D02*
X627313D01*
X618652Y-143996D02*
Y-138287D01*
X627313Y-143996D02*
Y-138287D01*
X618652D02*
X627313D01*
X618652Y-143996D02*
X627313D01*
X205260Y-382765D02*
Y-378435D01*
X207622Y-382765D02*
Y-378435D01*
X205260D02*
X207622D01*
X205260Y-382765D02*
X207622D01*
X209260D02*
X211622D01*
X209260Y-378435D02*
X211622D01*
Y-382765D02*
Y-378435D01*
X209260Y-382765D02*
Y-378435D01*
X217160Y-382765D02*
Y-378435D01*
X219522Y-382765D02*
Y-378435D01*
X217160D02*
X219522D01*
X217160Y-382765D02*
X219522D01*
X221460D02*
X223822D01*
X221460Y-378435D02*
X223822D01*
Y-382765D02*
Y-378435D01*
X221460Y-382765D02*
Y-378435D01*
X236760Y-382765D02*
X239122D01*
X236760Y-378435D02*
X239122D01*
Y-382765D02*
Y-378435D01*
X236760Y-382765D02*
Y-378435D01*
X240760Y-382765D02*
X243122D01*
X240760Y-378435D02*
X243122D01*
Y-382765D02*
Y-378435D01*
X240760Y-382765D02*
Y-378435D01*
X252260Y-382765D02*
X254622D01*
X252260Y-378435D02*
X254622D01*
Y-382765D02*
Y-378435D01*
X252260Y-382765D02*
Y-378435D01*
X255760Y-382765D02*
Y-378435D01*
X258122Y-382765D02*
Y-378435D01*
X255760D02*
X258122D01*
X255760Y-382765D02*
X258122D01*
X268260D02*
X270622D01*
X268260Y-378435D02*
X270622D01*
Y-382765D02*
Y-378435D01*
X268260Y-382765D02*
Y-378435D01*
X617717Y-122835D02*
X624016D01*
X617717Y-125984D02*
X624016D01*
X617717D02*
Y-122835D01*
X624016Y-125984D02*
Y-122835D01*
X617766Y-120177D02*
Y-116437D01*
X624262Y-120177D02*
Y-116437D01*
X617766D02*
X624262D01*
X617766Y-120177D02*
X624262D01*
X540065Y-126535D02*
X546561D01*
X540065Y-130276D02*
X546561D01*
X540065D02*
Y-126535D01*
X546561Y-130276D02*
Y-126535D01*
X575640Y-142028D02*
Y-135531D01*
X571900Y-142028D02*
Y-135531D01*
X575640D01*
X571900Y-142028D02*
X575640D01*
X560679Y-103445D02*
X567176D01*
X560679Y-107185D02*
X567176D01*
X560679D02*
Y-103445D01*
X567176Y-107185D02*
Y-103445D01*
X110177Y-261761D02*
X116673D01*
X110177Y-265502D02*
X116673D01*
X110177D02*
Y-261761D01*
X116673Y-265502D02*
Y-261761D01*
X220669Y-358316D02*
Y-353986D01*
X223031Y-358316D02*
Y-353986D01*
X220669Y-358316D02*
X223031D01*
X220669Y-353986D02*
X223031D01*
D179*
X558576Y-241280D02*
Y-225532D01*
X578261D01*
Y-241280D02*
Y-225532D01*
X558576Y-241280D02*
X578261D01*
X563576D02*
X578261D01*
X558576Y-236280D02*
X563576Y-241280D01*
X558576Y-236280D02*
Y-225532D01*
X578261D01*
Y-241280D02*
Y-225532D01*
X569156Y-138279D02*
Y-122531D01*
X549471D02*
X569156D01*
X549471Y-133280D02*
Y-122531D01*
Y-133280D02*
X554471Y-138279D01*
X569156D01*
X549471D02*
X569156D01*
Y-122531D01*
X549471D02*
X569156D01*
X549471Y-138279D02*
Y-122531D01*
D180*
X623592Y-124409D02*
D03*
M02*
